(lib_symbols
	(symbol "antmicroCapacitors0402:C_100n_0402"
			(pin_numbers
				(hide yes)
			)
			(pin_names
				(hide yes)
			)
			(exclude_from_sim no)
			(in_bom yes)
			(on_board yes)
			(property "Reference" "C"
				(at 20.32 -5.08 0)
				(effects
					(font
						(size 1.27 1.27)
						(thickness 0.15)
					)
					(justify left bottom)
				)
			)
			(property "Value" "C_100n_0402"
				(at 20.32 -10.16 0)
				(effects
					(font
						(size 1.27 1.27)
						(thickness 0.15)
					)
					(justify left bottom)
					(hide yes)
				)
			)
			(property "Footprint" "antmicro-footprints:C_0402_1005Metric"
				(at 20.32 -12.7 0)
				(effects
					(font
						(size 1.27 1.27)
						(thickness 0.15)
					)
					(justify left bottom)
					(hide yes)
				)
			)
			(property "Datasheet" "https://www.murata.com/products/productdetail?partno=GRM155R61H104KE14%23"
				(at 20.32 -15.24 0)
				(effects
					(font
						(size 1.27 1.27)
						(thickness 0.15)
					)
					(justify left bottom)
					(hide yes)
				)
			)
			(property "Description" "SMD Multilayer Ceramic Capacitor, 0.1 µF, 50 V, 0402 [1005 Metric], ± 10%, X5R, GRM Series"
				(at 20.32 -33.02 0)
				(effects
					(font
						(size 1.27 1.27)
					)
					(justify left bottom)
					(hide yes)
				)
			)
			(property "MPN" "GRM155R61H104KE14D"
				(at 20.32 -17.78 0)
				(effects
					(font
						(size 1.27 1.27)
						(thickness 0.15)
					)
					(justify left bottom)
					(hide yes)
				)
			)
			(property "Manufacturer" "Murata"
				(at 20.32 -20.32 0)
				(effects
					(font
						(size 1.27 1.27)
						(thickness 0.15)
					)
					(justify left bottom)
					(hide yes)
				)
			)
			(property "License" "Apache-2.0"
				(at 20.32 -22.86 0)
				(effects
					(font
						(size 1.27 1.27)
						(thickness 0.15)
					)
					(justify left bottom)
					(hide yes)
				)
			)
			(property "Author" "Antmicro"
				(at 20.32 -25.4 0)
				(effects
					(font
						(size 1.27 1.27)
						(thickness 0.15)
					)
					(justify left bottom)
					(hide yes)
				)
			)
			(property "Val" "100n"
				(at 20.32 -7.62 0)
				(effects
					(font
						(size 1.27 1.27)
						(thickness 0.15)
					)
					(justify left bottom)
				)
			)
			(property "Voltage" "50V"
				(at 20.32 -27.94 0)
				(effects
					(font
						(size 1.27 1.27)
					)
					(justify left bottom)
					(hide yes)
				)
			)
			(property "Dielectric" "X5R"
				(at 20.32 -30.48 0)
				(effects
					(font
						(size 1.27 1.27)
					)
					(justify left bottom)
					(hide yes)
				)
			)
			(property "ki_keywords" "0402, SMT, CAPACITOR, PASSIVE, CERAMIC, MLCC"
				(at 0 0 0)
				(effects
					(font
						(size 1.27 1.27)
					)
					(hide yes)
				)
			)
			(symbol "C_100n_0402_0_1"
				(polyline
					(pts
						(xy 2.032 -1.524) (xy 2.032 1.524)
					)
					(stroke
						(width 0.3048)
						(type default)
					)
					(fill
						(type none)
					)
				)
				(polyline
					(pts
						(xy 3.048 -1.524) (xy 3.048 1.524)
					)
					(stroke
						(width 0.3302)
						(type default)
					)
					(fill
						(type none)
					)
				)
			)
			(symbol "C_100n_0402_1_1"
				(pin passive line
					(at 0 0 0)
					(length 2.032)
					(name "~"
						(effects
							(font
								(size 1.27 1.27)
							)
						)
					)
					(number "1"
						(effects
							(font
								(size 1.27 1.27)
							)
						)
					)
				)
				(pin passive line
					(at 5.08 0 180)
					(length 2.032)
					(name "~"
						(effects
							(font
								(size 1.27 1.27)
							)
						)
					)
					(number "2"
						(effects
							(font
								(size 1.27 1.27)
							)
						)
					)
				)
			)
		)
	(symbol "antmicroCapacitors0402:C_10n_0402"
			(pin_numbers
				(hide yes)
			)
			(pin_names
				(hide yes)
			)
			(exclude_from_sim no)
			(in_bom yes)
			(on_board yes)
			(property "Reference" "C"
				(at 20.32 -5.08 0)
				(effects
					(font
						(size 1.27 1.27)
						(thickness 0.15)
					)
					(justify left bottom)
				)
			)
			(property "Value" "C_10n_0402"
				(at 20.32 -10.16 0)
				(effects
					(font
						(size 1.27 1.27)
						(thickness 0.15)
					)
					(justify left bottom)
					(hide yes)
				)
			)
			(property "Footprint" "antmicro-footprints:C_0402_1005Metric"
				(at 20.32 -12.7 0)
				(effects
					(font
						(size 1.27 1.27)
						(thickness 0.15)
					)
					(justify left bottom)
					(hide yes)
				)
			)
			(property "Datasheet" "https://www.murata.com/products/productdetail?partno=GRM155R71H103KA88%23"
				(at 20.32 -15.24 0)
				(effects
					(font
						(size 1.27 1.27)
						(thickness 0.15)
					)
					(justify left bottom)
					(hide yes)
				)
			)
			(property "Description" "SMD Multilayer Ceramic Capacitor, 10000 pF, 50 V, 0402 [1005 Metric], ± 10%, X7R, GRM Series"
				(at 20.32 -33.02 0)
				(effects
					(font
						(size 1.27 1.27)
					)
					(justify left bottom)
					(hide yes)
				)
			)
			(property "MPN" "GRM155R71H103KA88D"
				(at 20.32 -17.78 0)
				(effects
					(font
						(size 1.27 1.27)
						(thickness 0.15)
					)
					(justify left bottom)
					(hide yes)
				)
			)
			(property "Manufacturer" "Murata"
				(at 20.32 -20.32 0)
				(effects
					(font
						(size 1.27 1.27)
						(thickness 0.15)
					)
					(justify left bottom)
					(hide yes)
				)
			)
			(property "License" "Apache-2.0"
				(at 20.32 -22.86 0)
				(effects
					(font
						(size 1.27 1.27)
						(thickness 0.15)
					)
					(justify left bottom)
					(hide yes)
				)
			)
			(property "Author" "Antmicro"
				(at 20.32 -25.4 0)
				(effects
					(font
						(size 1.27 1.27)
						(thickness 0.15)
					)
					(justify left bottom)
					(hide yes)
				)
			)
			(property "Val" "10n"
				(at 20.32 -7.62 0)
				(effects
					(font
						(size 1.27 1.27)
						(thickness 0.15)
					)
					(justify left bottom)
				)
			)
			(property "Voltage" "50V"
				(at 20.32 -27.94 0)
				(effects
					(font
						(size 1.27 1.27)
					)
					(justify left bottom)
					(hide yes)
				)
			)
			(property "Dielectric" "X7R"
				(at 20.32 -30.48 0)
				(effects
					(font
						(size 1.27 1.27)
					)
					(justify left bottom)
					(hide yes)
				)
			)
			(property "ki_keywords" "0402, SMT, CAPACITOR, PASSIVE"
				(at 0 0 0)
				(effects
					(font
						(size 1.27 1.27)
					)
					(hide yes)
				)
			)
			(symbol "C_10n_0402_0_1"
				(polyline
					(pts
						(xy 2.032 -1.524) (xy 2.032 1.524)
					)
					(stroke
						(width 0.3048)
						(type default)
					)
					(fill
						(type none)
					)
				)
				(polyline
					(pts
						(xy 3.048 -1.524) (xy 3.048 1.524)
					)
					(stroke
						(width 0.3302)
						(type default)
					)
					(fill
						(type none)
					)
				)
			)
			(symbol "C_10n_0402_1_1"
				(pin passive line
					(at 0 0 0)
					(length 2.032)
					(name "~"
						(effects
							(font
								(size 1.27 1.27)
							)
						)
					)
					(number "1"
						(effects
							(font
								(size 1.27 1.27)
							)
						)
					)
				)
				(pin passive line
					(at 5.08 0 180)
					(length 2.032)
					(name "~"
						(effects
							(font
								(size 1.27 1.27)
							)
						)
					)
					(number "2"
						(effects
							(font
								(size 1.27 1.27)
							)
						)
					)
				)
			)
		)
	(symbol "antmicroCapacitors0402:C_1u_0402"
			(pin_numbers
				(hide yes)
			)
			(pin_names
				(hide yes)
			)
			(exclude_from_sim no)
			(in_bom yes)
			(on_board yes)
			(property "Reference" "C"
				(at 20.32 -5.08 0)
				(effects
					(font
						(size 1.27 1.27)
						(thickness 0.15)
					)
					(justify left bottom)
				)
			)
			(property "Value" "C_1u_0402"
				(at 20.32 -10.16 0)
				(effects
					(font
						(size 1.27 1.27)
						(thickness 0.15)
					)
					(justify left bottom)
					(hide yes)
				)
			)
			(property "Footprint" "antmicro-footprints:C_0402_1005Metric"
				(at 20.32 -12.7 0)
				(effects
					(font
						(size 1.27 1.27)
						(thickness 0.15)
					)
					(justify left bottom)
					(hide yes)
				)
			)
			(property "Datasheet" "https://product.tdk.com/en/search/capacitor/ceramic/mlcc/info?part_no=C1005X6S1A105K050BC"
				(at 20.32 -15.24 0)
				(effects
					(font
						(size 1.27 1.27)
						(thickness 0.15)
					)
					(justify left bottom)
					(hide yes)
				)
			)
			(property "Description" "SMD Multilayer Ceramic Capacitor, 1 µF, 10 V, 0402 [1005 Metric], ± 10%, X6S, C"
				(at 20.32 -33.02 0)
				(effects
					(font
						(size 1.27 1.27)
					)
					(justify left bottom)
					(hide yes)
				)
			)
			(property "MPN" "C1005X6S1A105K050BC"
				(at 20.32 -17.78 0)
				(effects
					(font
						(size 1.27 1.27)
						(thickness 0.15)
					)
					(justify left bottom)
					(hide yes)
				)
			)
			(property "Manufacturer" "TDK"
				(at 20.32 -20.32 0)
				(effects
					(font
						(size 1.27 1.27)
						(thickness 0.15)
					)
					(justify left bottom)
					(hide yes)
				)
			)
			(property "License" "Apache-2.0"
				(at 20.32 -22.86 0)
				(effects
					(font
						(size 1.27 1.27)
						(thickness 0.15)
					)
					(justify left bottom)
					(hide yes)
				)
			)
			(property "Author" "Antmicro"
				(at 20.32 -25.4 0)
				(effects
					(font
						(size 1.27 1.27)
						(thickness 0.15)
					)
					(justify left bottom)
					(hide yes)
				)
			)
			(property "Val" "1u"
				(at 20.32 -7.62 0)
				(effects
					(font
						(size 1.27 1.27)
						(thickness 0.15)
					)
					(justify left bottom)
				)
			)
			(property "Voltage" ""
				(at 20.32 -27.94 0)
				(effects
					(font
						(size 1.27 1.27)
					)
					(justify left bottom)
					(hide yes)
				)
			)
			(property "Dielectric" ""
				(at 20.32 -30.48 0)
				(effects
					(font
						(size 1.27 1.27)
					)
					(justify left bottom)
					(hide yes)
				)
			)
			(property "ki_keywords" "0402, SMT, CAPACITOR, PASSIVE, CERAMIC, MLCC"
				(at 0 0 0)
				(effects
					(font
						(size 1.27 1.27)
					)
					(hide yes)
				)
			)
			(symbol "C_1u_0402_0_1"
				(polyline
					(pts
						(xy 2.032 -1.524) (xy 2.032 1.524)
					)
					(stroke
						(width 0.3048)
						(type default)
					)
					(fill
						(type none)
					)
				)
				(polyline
					(pts
						(xy 3.048 -1.524) (xy 3.048 1.524)
					)
					(stroke
						(width 0.3302)
						(type default)
					)
					(fill
						(type none)
					)
				)
			)
			(symbol "C_1u_0402_1_1"
				(pin passive line
					(at 0 0 0)
					(length 2.032)
					(name "~"
						(effects
							(font
								(size 1.27 1.27)
							)
						)
					)
					(number "1"
						(effects
							(font
								(size 1.27 1.27)
							)
						)
					)
				)
				(pin passive line
					(at 5.08 0 180)
					(length 2.032)
					(name "~"
						(effects
							(font
								(size 1.27 1.27)
							)
						)
					)
					(number "2"
						(effects
							(font
								(size 1.27 1.27)
							)
						)
					)
				)
			)
		)
	(symbol "antmicroCapacitors0402:C_33p_0402"
			(pin_numbers
				(hide yes)
			)
			(pin_names
				(hide yes)
			)
			(exclude_from_sim no)
			(in_bom yes)
			(on_board yes)
			(property "Reference" "C"
				(at 20.32 -5.08 0)
				(effects
					(font
						(size 1.27 1.27)
						(thickness 0.15)
					)
					(justify left bottom)
				)
			)
			(property "Value" "C_33p_0402"
				(at 20.32 -10.16 0)
				(effects
					(font
						(size 1.27 1.27)
						(thickness 0.15)
					)
					(justify left bottom)
					(hide yes)
				)
			)
			(property "Footprint" "antmicro-footprints:C_0402_1005Metric"
				(at 20.32 -12.7 0)
				(effects
					(font
						(size 1.27 1.27)
						(thickness 0.15)
					)
					(justify left bottom)
					(hide yes)
				)
			)
			(property "Datasheet" "https://spicat.kyocera-avx.com/product/mlcc/chartview/04025A330FAT2A/"
				(at 20.32 -15.24 0)
				(effects
					(font
						(size 1.27 1.27)
						(thickness 0.15)
					)
					(justify left bottom)
					(hide yes)
				)
			)
			(property "Description" "SMD Multilayer Ceramic Capacitor, 33 pF, 50 V, 0402 [1005 Metric], ± 5%, C0G / NP0, MC"
				(at 20.32 -33.02 0)
				(effects
					(font
						(size 1.27 1.27)
					)
					(justify left bottom)
					(hide yes)
				)
			)
			(property "MPN" "04025A330FAT2A"
				(at 20.32 -17.78 0)
				(effects
					(font
						(size 1.27 1.27)
						(thickness 0.15)
					)
					(justify left bottom)
					(hide yes)
				)
			)
			(property "Manufacturer" "KYOCERA AVX"
				(at 20.32 -20.32 0)
				(effects
					(font
						(size 1.27 1.27)
						(thickness 0.15)
					)
					(justify left bottom)
					(hide yes)
				)
			)
			(property "License" "Apache-2.0"
				(at 20.32 -22.86 0)
				(effects
					(font
						(size 1.27 1.27)
						(thickness 0.15)
					)
					(justify left bottom)
					(hide yes)
				)
			)
			(property "Author" "Antmicro"
				(at 20.32 -25.4 0)
				(effects
					(font
						(size 1.27 1.27)
						(thickness 0.15)
					)
					(justify left bottom)
					(hide yes)
				)
			)
			(property "Val" "33p"
				(at 20.32 -7.62 0)
				(effects
					(font
						(size 1.27 1.27)
						(thickness 0.15)
					)
					(justify left bottom)
				)
			)
			(property "Voltage" ""
				(at 20.32 -27.94 0)
				(effects
					(font
						(size 1.27 1.27)
					)
					(justify left bottom)
					(hide yes)
				)
			)
			(property "Dielectric" ""
				(at 20.32 -30.48 0)
				(effects
					(font
						(size 1.27 1.27)
					)
					(justify left bottom)
					(hide yes)
				)
			)
			(property "ki_keywords" "0402, SMT, CAPACITOR, PASSIVE"
				(at 0 0 0)
				(effects
					(font
						(size 1.27 1.27)
					)
					(hide yes)
				)
			)
			(symbol "C_33p_0402_0_1"
				(polyline
					(pts
						(xy 2.032 -1.524) (xy 2.032 1.524)
					)
					(stroke
						(width 0.3048)
						(type default)
					)
					(fill
						(type none)
					)
				)
				(polyline
					(pts
						(xy 3.048 -1.524) (xy 3.048 1.524)
					)
					(stroke
						(width 0.3302)
						(type default)
					)
					(fill
						(type none)
					)
				)
			)
			(symbol "C_33p_0402_1_1"
				(pin passive line
					(at 0 0 0)
					(length 2.032)
					(name "~"
						(effects
							(font
								(size 1.27 1.27)
							)
						)
					)
					(number "1"
						(effects
							(font
								(size 1.27 1.27)
							)
						)
					)
				)
				(pin passive line
					(at 5.08 0 180)
					(length 2.032)
					(name "~"
						(effects
							(font
								(size 1.27 1.27)
							)
						)
					)
					(number "2"
						(effects
							(font
								(size 1.27 1.27)
							)
						)
					)
				)
			)
		)
	(symbol "antmicroCapacitors0402:C_470n_0402"
			(pin_numbers
				(hide yes)
			)
			(pin_names
				(hide yes)
			)
			(exclude_from_sim no)
			(in_bom yes)
			(on_board yes)
			(property "Reference" "C"
				(at 20.32 -5.08 0)
				(effects
					(font
						(size 1.27 1.27)
						(thickness 0.15)
					)
					(justify left bottom)
				)
			)
			(property "Value" "C_470n_0402"
				(at 20.32 -10.16 0)
				(effects
					(font
						(size 1.27 1.27)
						(thickness 0.15)
					)
					(justify left bottom)
					(hide yes)
				)
			)
			(property "Footprint" "antmicro-footprints:C_0402_1005Metric"
				(at 20.32 -12.7 0)
				(effects
					(font
						(size 1.27 1.27)
						(thickness 0.15)
					)
					(justify left bottom)
					(hide yes)
				)
			)
			(property "Datasheet" "https://product.tdk.com/en/search/capacitor/ceramic/mlcc/info?part_no=C1005X5R1E474M050BB"
				(at 20.32 -15.24 0)
				(effects
					(font
						(size 1.27 1.27)
						(thickness 0.15)
					)
					(justify left bottom)
					(hide yes)
				)
			)
			(property "Description" "SMD Multilayer Ceramic Capacitor, 0.47 µF, 25 V, 0402 [1005 Metric], ± 20%, X5R, C"
				(at 20.32 -33.02 0)
				(effects
					(font
						(size 1.27 1.27)
					)
					(justify left bottom)
					(hide yes)
				)
			)
			(property "MPN" "C1005X5R1E474M050BB"
				(at 20.32 -17.78 0)
				(effects
					(font
						(size 1.27 1.27)
						(thickness 0.15)
					)
					(justify left bottom)
					(hide yes)
				)
			)
			(property "Manufacturer" "TDK"
				(at 20.32 -20.32 0)
				(effects
					(font
						(size 1.27 1.27)
						(thickness 0.15)
					)
					(justify left bottom)
					(hide yes)
				)
			)
			(property "License" "Apache-2.0"
				(at 20.32 -22.86 0)
				(effects
					(font
						(size 1.27 1.27)
						(thickness 0.15)
					)
					(justify left bottom)
					(hide yes)
				)
			)
			(property "Author" "Antmicro"
				(at 20.32 -25.4 0)
				(effects
					(font
						(size 1.27 1.27)
						(thickness 0.15)
					)
					(justify left bottom)
					(hide yes)
				)
			)
			(property "Val" "470n"
				(at 20.32 -7.62 0)
				(effects
					(font
						(size 1.27 1.27)
						(thickness 0.15)
					)
					(justify left bottom)
				)
			)
			(property "Voltage" ""
				(at 20.32 -27.94 0)
				(effects
					(font
						(size 1.27 1.27)
					)
					(justify left bottom)
					(hide yes)
				)
			)
			(property "Dielectric" ""
				(at 20.32 -30.48 0)
				(effects
					(font
						(size 1.27 1.27)
					)
					(justify left bottom)
					(hide yes)
				)
			)
			(property "ki_keywords" "0402, SMT, CAPACITOR, PASSIVE, CERAMIC, MLCC"
				(at 0 0 0)
				(effects
					(font
						(size 1.27 1.27)
					)
					(hide yes)
				)
			)
			(symbol "C_470n_0402_0_1"
				(polyline
					(pts
						(xy 2.032 -1.524) (xy 2.032 1.524)
					)
					(stroke
						(width 0.3048)
						(type default)
					)
					(fill
						(type none)
					)
				)
				(polyline
					(pts
						(xy 3.048 -1.524) (xy 3.048 1.524)
					)
					(stroke
						(width 0.3302)
						(type default)
					)
					(fill
						(type none)
					)
				)
			)
			(symbol "C_470n_0402_1_1"
				(pin passive line
					(at 0 0 0)
					(length 2.032)
					(name "~"
						(effects
							(font
								(size 1.27 1.27)
							)
						)
					)
					(number "1"
						(effects
							(font
								(size 1.27 1.27)
							)
						)
					)
				)
				(pin passive line
					(at 5.08 0 180)
					(length 2.032)
					(name "~"
						(effects
							(font
								(size 1.27 1.27)
							)
						)
					)
					(number "2"
						(effects
							(font
								(size 1.27 1.27)
							)
						)
					)
				)
			)
		)
	(symbol "antmicroCapacitors0402:C_47n_0402"
			(pin_numbers
				(hide yes)
			)
			(pin_names
				(hide yes)
			)
			(exclude_from_sim no)
			(in_bom yes)
			(on_board yes)
			(property "Reference" "C"
				(at 20.32 -5.08 0)
				(effects
					(font
						(size 1.27 1.27)
						(thickness 0.15)
					)
					(justify left bottom)
				)
			)
			(property "Value" "C_47n_0402"
				(at 20.32 -10.16 0)
				(effects
					(font
						(size 1.27 1.27)
						(thickness 0.15)
					)
					(justify left bottom)
					(hide yes)
				)
			)
			(property "Footprint" "antmicro-footprints:C_0402_1005Metric"
				(at 20.32 -12.7 0)
				(effects
					(font
						(size 1.27 1.27)
						(thickness 0.15)
					)
					(justify left bottom)
					(hide yes)
				)
			)
			(property "Datasheet" "https://www.murata.com/en-us/products/productdetail?partno=GRM155R61C473KA01%23"
				(at 20.32 -15.24 0)
				(effects
					(font
						(size 1.27 1.27)
						(thickness 0.15)
					)
					(justify left bottom)
					(hide yes)
				)
			)
			(property "Description" "SMD Multilayer Ceramic Capacitor, 47000 pF, 16 V, 0402 [1005 Metric], ± 10%, X5R, MC"
				(at 20.32 -33.02 0)
				(effects
					(font
						(size 1.27 1.27)
					)
					(justify left bottom)
					(hide yes)
				)
			)
			(property "MPN" "GRM155R61C473KA01D"
				(at 20.32 -17.78 0)
				(effects
					(font
						(size 1.27 1.27)
						(thickness 0.15)
					)
					(justify left bottom)
					(hide yes)
				)
			)
			(property "Manufacturer" "Murata"
				(at 20.32 -20.32 0)
				(effects
					(font
						(size 1.27 1.27)
						(thickness 0.15)
					)
					(justify left bottom)
					(hide yes)
				)
			)
			(property "License" "Apache-2.0"
				(at 20.32 -22.86 0)
				(effects
					(font
						(size 1.27 1.27)
						(thickness 0.15)
					)
					(justify left bottom)
					(hide yes)
				)
			)
			(property "Author" "Antmicro"
				(at 20.32 -25.4 0)
				(effects
					(font
						(size 1.27 1.27)
						(thickness 0.15)
					)
					(justify left bottom)
					(hide yes)
				)
			)
			(property "Val" "47n"
				(at 20.32 -7.62 0)
				(effects
					(font
						(size 1.27 1.27)
						(thickness 0.15)
					)
					(justify left bottom)
				)
			)
			(property "Voltage" ""
				(at 20.32 -27.94 0)
				(effects
					(font
						(size 1.27 1.27)
					)
					(justify left bottom)
					(hide yes)
				)
			)
			(property "Dielectric" ""
				(at 20.32 -30.48 0)
				(effects
					(font
						(size 1.27 1.27)
					)
					(justify left bottom)
					(hide yes)
				)
			)
			(property "ki_keywords" "0402, SMT, CAPACITOR, PASSIVE"
				(at 0 0 0)
				(effects
					(font
						(size 1.27 1.27)
					)
					(hide yes)
				)
			)
			(symbol "C_47n_0402_0_1"
				(polyline
					(pts
						(xy 2.032 -1.524) (xy 2.032 1.524)
					)
					(stroke
						(width 0.3048)
						(type default)
					)
					(fill
						(type none)
					)
				)
				(polyline
					(pts
						(xy 3.048 -1.524) (xy 3.048 1.524)
					)
					(stroke
						(width 0.3302)
						(type default)
					)
					(fill
						(type none)
					)
				)
			)
			(symbol "C_47n_0402_1_1"
				(pin passive line
					(at 0 0 0)
					(length 2.032)
					(name "~"
						(effects
							(font
								(size 1.27 1.27)
							)
						)
					)
					(number "1"
						(effects
							(font
								(size 1.27 1.27)
							)
						)
					)
				)
				(pin passive line
					(at 5.08 0 180)
					(length 2.032)
					(name "~"
						(effects
							(font
								(size 1.27 1.27)
							)
						)
					)
					(number "2"
						(effects
							(font
								(size 1.27 1.27)
							)
						)
					)
				)
			)
		)
	(symbol "antmicroCapacitors0402:C_47p_0402"
			(pin_numbers
				(hide yes)
			)
			(pin_names
				(hide yes)
			)
			(exclude_from_sim no)
			(in_bom yes)
			(on_board yes)
			(property "Reference" "C"
				(at 20.32 -5.08 0)
				(effects
					(font
						(size 1.27 1.27)
						(thickness 0.15)
					)
					(justify left bottom)
				)
			)
			(property "Value" "C_47p_0402"
				(at 20.32 -10.16 0)
				(effects
					(font
						(size 1.27 1.27)
						(thickness 0.15)
					)
					(justify left bottom)
					(hide yes)
				)
			)
			(property "Footprint" "antmicro-footprints:C_0402_1005Metric"
				(at 20.32 -12.7 0)
				(effects
					(font
						(size 1.27 1.27)
						(thickness 0.15)
					)
					(justify left bottom)
					(hide yes)
				)
			)
			(property "Datasheet" "https://www.kemet.com/en/us/capacitors/product/C0402C470J5GACTU.html"
				(at 20.32 -15.24 0)
				(effects
					(font
						(size 1.27 1.27)
						(thickness 0.15)
					)
					(justify left bottom)
					(hide yes)
				)
			)
			(property "Description" "SMD Multilayer Ceramic Capacitor, 47 pF, 50 V, 0402 [1005 Metric], ± 5%, C0G / NP0, C Series KEMET"
				(at 20.32 -33.02 0)
				(effects
					(font
						(size 1.27 1.27)
					)
					(justify left bottom)
					(hide yes)
				)
			)
			(property "MPN" "C0402C470J5GACTU"
				(at 20.32 -17.78 0)
				(effects
					(font
						(size 1.27 1.27)
						(thickness 0.15)
					)
					(justify left bottom)
					(hide yes)
				)
			)
			(property "Manufacturer" "KEMET"
				(at 20.32 -20.32 0)
				(effects
					(font
						(size 1.27 1.27)
						(thickness 0.15)
					)
					(justify left bottom)
					(hide yes)
				)
			)
			(property "License" "Apache-2.0"
				(at 20.32 -22.86 0)
				(effects
					(font
						(size 1.27 1.27)
						(thickness 0.15)
					)
					(justify left bottom)
					(hide yes)
				)
			)
			(property "Author" "Antmicro"
				(at 20.32 -25.4 0)
				(effects
					(font
						(size 1.27 1.27)
						(thickness 0.15)
					)
					(justify left bottom)
					(hide yes)
				)
			)
			(property "Val" "47p"
				(at 20.32 -7.62 0)
				(effects
					(font
						(size 1.27 1.27)
						(thickness 0.15)
					)
					(justify left bottom)
				)
			)
			(property "Voltage" ""
				(at 20.32 -27.94 0)
				(effects
					(font
						(size 1.27 1.27)
					)
					(justify left bottom)
					(hide yes)
				)
			)
			(property "Dielectric" "C0G"
				(at 20.32 -30.48 0)
				(effects
					(font
						(size 1.27 1.27)
					)
					(justify left bottom)
					(hide yes)
				)
			)
			(property "ki_keywords" "0402, SMT, CAPACITOR, PASSIVE, CERAMIC, MLCC"
				(at 0 0 0)
				(effects
					(font
						(size 1.27 1.27)
					)
					(hide yes)
				)
			)
			(symbol "C_47p_0402_0_1"
				(polyline
					(pts
						(xy 2.032 -1.524) (xy 2.032 1.524)
					)
					(stroke
						(width 0.3048)
						(type default)
					)
					(fill
						(type none)
					)
				)
				(polyline
					(pts
						(xy 3.048 -1.524) (xy 3.048 1.524)
					)
					(stroke
						(width 0.3302)
						(type default)
					)
					(fill
						(type none)
					)
				)
			)
			(symbol "C_47p_0402_1_1"
				(pin passive line
					(at 0 0 0)
					(length 2.032)
					(name "~"
						(effects
							(font
								(size 1.27 1.27)
							)
						)
					)
					(number "1"
						(effects
							(font
								(size 1.27 1.27)
							)
						)
					)
				)
				(pin passive line
					(at 5.08 0 180)
					(length 2.032)
					(name "~"
						(effects
							(font
								(size 1.27 1.27)
							)
						)
					)
					(number "2"
						(effects
							(font
								(size 1.27 1.27)
							)
						)
					)
				)
			)
		)
	(symbol "antmicroCapacitors0402:C_4u7_0402"
			(pin_numbers
				(hide yes)
			)
			(pin_names
				(hide yes)
			)
			(exclude_from_sim no)
			(in_bom yes)
			(on_board yes)
			(property "Reference" "C"
				(at 20.32 -5.08 0)
				(effects
					(font
						(size 1.27 1.27)
						(thickness 0.15)
					)
					(justify left bottom)
				)
			)
			(property "Value" "C_4u7_0402"
				(at 20.32 -10.16 0)
				(effects
					(font
						(size 1.27 1.27)
						(thickness 0.15)
					)
					(justify left bottom)
					(hide yes)
				)
			)
			(property "Footprint" "antmicro-footprints:C_0402_1005Metric"
				(at 20.32 -12.7 0)
				(effects
					(font
						(size 1.27 1.27)
						(thickness 0.15)
					)
					(justify left bottom)
					(hide yes)
				)
			)
			(property "Datasheet" "https://www.murata.com/products/productdetail?partno=GRM155R61A475MEAA%23"
				(at 20.32 -15.24 0)
				(effects
					(font
						(size 1.27 1.27)
						(thickness 0.15)
					)
					(justify left bottom)
					(hide yes)
				)
			)
			(property "Description" "SMD Multilayer Ceramic Capacitor, 4.7 µF, 10 V, 0402 [1005 Metric], ± 20%, X5R, GRM Series"
				(at 20.32 -33.02 0)
				(effects
					(font
						(size 1.27 1.27)
					)
					(justify left bottom)
					(hide yes)
				)
			)
			(property "MPN" "GRM155R61A475MEAAD"
				(at 20.32 -17.78 0)
				(effects
					(font
						(size 1.27 1.27)
						(thickness 0.15)
					)
					(justify left bottom)
					(hide yes)
				)
			)
			(property "Manufacturer" "Murata"
				(at 20.32 -20.32 0)
				(effects
					(font
						(size 1.27 1.27)
						(thickness 0.15)
					)
					(justify left bottom)
					(hide yes)
				)
			)
			(property "License" "Apache-2.0"
				(at 20.32 -22.86 0)
				(effects
					(font
						(size 1.27 1.27)
						(thickness 0.15)
					)
					(justify left bottom)
					(hide yes)
				)
			)
			(property "Author" "Antmicro"
				(at 20.32 -25.4 0)
				(effects
					(font
						(size 1.27 1.27)
						(thickness 0.15)
					)
					(justify left bottom)
					(hide yes)
				)
			)
			(property "Val" "4u7"
				(at 20.32 -7.62 0)
				(effects
					(font
						(size 1.27 1.27)
						(thickness 0.15)
					)
					(justify left bottom)
				)
			)
			(property "Voltage" ""
				(at 20.32 -27.94 0)
				(effects
					(font
						(size 1.27 1.27)
					)
					(justify left bottom)
					(hide yes)
				)
			)
			(property "Dielectric" ""
				(at 20.32 -30.48 0)
				(effects
					(font
						(size 1.27 1.27)
					)
					(justify left bottom)
					(hide yes)
				)
			)
			(property "ki_keywords" "0402, SMT, CAPACITOR, PASSIVE"
				(at 0 0 0)
				(effects
					(font
						(size 1.27 1.27)
					)
					(hide yes)
				)
			)
			(symbol "C_4u7_0402_0_1"
				(polyline
					(pts
						(xy 2.032 -1.524) (xy 2.032 1.524)
					)
					(stroke
						(width 0.3048)
						(type default)
					)
					(fill
						(type none)
					)
				)
				(polyline
					(pts
						(xy 3.048 -1.524) (xy 3.048 1.524)
					)
					(stroke
						(width 0.3302)
						(type default)
					)
					(fill
						(type none)
					)
				)
			)
			(symbol "C_4u7_0402_1_1"
				(pin passive line
					(at 0 0 0)
					(length 2.032)
					(name "~"
						(effects
							(font
								(size 1.27 1.27)
							)
						)
					)
					(number "1"
						(effects
							(font
								(size 1.27 1.27)
							)
						)
					)
				)
				(pin passive line
					(at 5.08 0 180)
					(length 2.032)
					(name "~"
						(effects
							(font
								(size 1.27 1.27)
							)
						)
					)
					(number "2"
						(effects
							(font
								(size 1.27 1.27)
							)
						)
					)
				)
			)
		)
	(symbol "antmicroCapacitors0603:C_10u_0603"
			(pin_numbers
				(hide yes)
			)
			(pin_names
				(hide yes)
			)
			(exclude_from_sim no)
			(in_bom yes)
			(on_board yes)
			(property "Reference" "C"
				(at 20.32 -5.08 0)
				(effects
					(font
						(size 1.27 1.27)
						(thickness 0.15)
					)
					(justify left bottom)
				)
			)
			(property "Value" "C_10u_0603"
				(at 20.32 -10.16 0)
				(effects
					(font
						(size 1.27 1.27)
						(thickness 0.15)
					)
					(justify left bottom)
					(hide yes)
				)
			)
			(property "Footprint" "antmicro-footprints:C_0603_1608Metric"
				(at 20.32 -12.7 0)
				(effects
					(font
						(size 1.27 1.27)
						(thickness 0.15)
					)
					(justify left bottom)
					(hide yes)
				)
			)
			(property "Datasheet" "https://www.murata.com/products/productdetail?partno=GRM188R61A106KE69%23"
				(at 20.32 -15.24 0)
				(effects
					(font
						(size 1.27 1.27)
						(thickness 0.15)
					)
					(justify left bottom)
					(hide yes)
				)
			)
			(property "Description" "SMD Multilayer Ceramic Capacitor, 10 µF, 10 V, 0603 [1608 Metric], ± 10%, X5R, GRM Series"
				(at 20.32 -30.48 0)
				(effects
					(font
						(size 1.27 1.27)
					)
					(justify left bottom)
					(hide yes)
				)
			)
			(property "MPN" "GRM188R61A106KE69D"
				(at 20.32 -17.78 0)
				(effects
					(font
						(size 1.27 1.27)
						(thickness 0.15)
					)
					(justify left bottom)
					(hide yes)
				)
			)
			(property "Manufacturer" "Murata"
				(at 20.32 -20.32 0)
				(effects
					(font
						(size 1.27 1.27)
						(thickness 0.15)
					)
					(justify left bottom)
					(hide yes)
				)
			)
			(property "License" "Apache-2.0"
				(at 20.32 -22.86 0)
				(effects
					(font
						(size 1.27 1.27)
						(thickness 0.15)
					)
					(justify left bottom)
					(hide yes)
				)
			)
			(property "Author" "Antmicro"
				(at 20.32 -25.4 0)
				(effects
					(font
						(size 1.27 1.27)
						(thickness 0.15)
					)
					(justify left bottom)
					(hide yes)
				)
			)
			(property "Val" "10u"
				(at 20.32 -7.62 0)
				(effects
					(font
						(size 1.27 1.27)
						(thickness 0.15)
					)
					(justify left bottom)
				)
			)
			(property "Voltage" ""
				(at 20.32 -27.94 0)
				(effects
					(font
						(size 1.27 1.27)
					)
					(justify left bottom)
					(hide yes)
				)
			)
			(property "Dielectric" "template_dielectric"
				(at 20.32 -30.48 0)
				(effects
					(font
						(size 1.27 1.27)
					)
					(justify left bottom)
					(hide yes)
				)
			)
			(property "ki_keywords" "0603, SMT, CAPACITOR, PASSIVE, CERAMIC, MLCC"
				(at 0 0 0)
				(effects
					(font
						(size 1.27 1.27)
					)
					(hide yes)
				)
			)
			(symbol "C_10u_0603_0_1"
				(polyline
					(pts
						(xy 2.032 -1.524) (xy 2.032 1.524)
					)
					(stroke
						(width 0.3048)
						(type default)
					)
					(fill
						(type none)
					)
				)
				(polyline
					(pts
						(xy 3.048 -1.524) (xy 3.048 1.524)
					)
					(stroke
						(width 0.3302)
						(type default)
					)
					(fill
						(type none)
					)
				)
			)
			(symbol "C_10u_0603_1_1"
				(pin passive line
					(at 0 0 0)
					(length 2.032)
					(name "~"
						(effects
							(font
								(size 1.27 1.27)
							)
						)
					)
					(number "1"
						(effects
							(font
								(size 1.27 1.27)
							)
						)
					)
				)
				(pin passive line
					(at 5.08 0 180)
					(length 2.032)
					(name "~"
						(effects
							(font
								(size 1.27 1.27)
							)
						)
					)
					(number "2"
						(effects
							(font
								(size 1.27 1.27)
							)
						)
					)
				)
			)
		)
	(symbol "antmicroCapacitors0603:C_1u_0603"
			(pin_numbers
				(hide yes)
			)
			(pin_names
				(hide yes)
			)
			(exclude_from_sim no)
			(in_bom yes)
			(on_board yes)
			(property "Reference" "C"
				(at 20.32 -5.08 0)
				(effects
					(font
						(size 1.27 1.27)
						(thickness 0.15)
					)
					(justify left bottom)
				)
			)
			(property "Value" "C_1u_0603"
				(at 20.32 -10.16 0)
				(effects
					(font
						(size 1.27 1.27)
						(thickness 0.15)
					)
					(justify left bottom)
					(hide yes)
				)
			)
			(property "Footprint" "antmicro-footprints:C_0603_1608Metric"
				(at 20.32 -12.7 0)
				(effects
					(font
						(size 1.27 1.27)
						(thickness 0.15)
					)
					(justify left bottom)
					(hide yes)
				)
			)
			(property "Datasheet" "https://spicat.kyocera-avx.com/product/mlcc/chartview/0603YD105KAT2A/"
				(at 20.32 -15.24 0)
				(effects
					(font
						(size 1.27 1.27)
						(thickness 0.15)
					)
					(justify left bottom)
					(hide yes)
				)
			)
			(property "Description" "SMD Multilayer Ceramic Capacitor, 1 µF, 16 V, 0603 [1608 Metric], ± 10%, X5R, AVX 0603 MLCC"
				(at 20.32 -33.02 0)
				(effects
					(font
						(size 1.27 1.27)
					)
					(justify left bottom)
					(hide yes)
				)
			)
			(property "MPN" "0603YD105KAT2A"
				(at 20.32 -17.78 0)
				(effects
					(font
						(size 1.27 1.27)
						(thickness 0.15)
					)
					(justify left bottom)
					(hide yes)
				)
			)
			(property "Manufacturer" "KYOCERA AVX"
				(at 20.32 -20.32 0)
				(effects
					(font
						(size 1.27 1.27)
						(thickness 0.15)
					)
					(justify left bottom)
					(hide yes)
				)
			)
			(property "License" "Apache-2.0"
				(at 20.32 -22.86 0)
				(effects
					(font
						(size 1.27 1.27)
						(thickness 0.15)
					)
					(justify left bottom)
					(hide yes)
				)
			)
			(property "Author" "Antmicro"
				(at 20.32 -25.4 0)
				(effects
					(font
						(size 1.27 1.27)
						(thickness 0.15)
					)
					(justify left bottom)
					(hide yes)
				)
			)
			(property "Val" "1u"
				(at 20.32 -7.62 0)
				(effects
					(font
						(size 1.27 1.27)
						(thickness 0.15)
					)
					(justify left bottom)
				)
			)
			(property "Voltage" ""
				(at 20.32 -27.94 0)
				(effects
					(font
						(size 1.27 1.27)
					)
					(justify left bottom)
					(hide yes)
				)
			)
			(property "Dielectric" ""
				(at 20.32 -30.48 0)
				(effects
					(font
						(size 1.27 1.27)
					)
					(justify left bottom)
					(hide yes)
				)
			)
			(property "ki_keywords" "0603, SMT, CAPACITOR, PASSIVE, MLCC"
				(at 0 0 0)
				(effects
					(font
						(size 1.27 1.27)
					)
					(hide yes)
				)
			)
			(symbol "C_1u_0603_0_1"
				(polyline
					(pts
						(xy 2.032 -1.524) (xy 2.032 1.524)
					)
					(stroke
						(width 0.3048)
						(type default)
					)
					(fill
						(type none)
					)
				)
				(polyline
					(pts
						(xy 3.048 -1.524) (xy 3.048 1.524)
					)
					(stroke
						(width 0.3302)
						(type default)
					)
					(fill
						(type none)
					)
				)
			)
			(symbol "C_1u_0603_1_1"
				(pin passive line
					(at 0 0 0)
					(length 2.032)
					(name "~"
						(effects
							(font
								(size 1.27 1.27)
							)
						)
					)
					(number "1"
						(effects
							(font
								(size 1.27 1.27)
							)
						)
					)
				)
				(pin passive line
					(at 5.08 0 180)
					(length 2.032)
					(name "~"
						(effects
							(font
								(size 1.27 1.27)
							)
						)
					)
					(number "2"
						(effects
							(font
								(size 1.27 1.27)
							)
						)
					)
				)
			)
		)
	(symbol "antmicroCapacitors0603:C_22u_0603"
			(pin_numbers
				(hide yes)
			)
			(pin_names
				(hide yes)
			)
			(exclude_from_sim no)
			(in_bom yes)
			(on_board yes)
			(property "Reference" "C"
				(at 20.32 -5.08 0)
				(effects
					(font
						(size 1.27 1.27)
						(thickness 0.15)
					)
					(justify left bottom)
				)
			)
			(property "Value" "C_22u_0603"
				(at 20.32 -10.16 0)
				(effects
					(font
						(size 1.27 1.27)
						(thickness 0.15)
					)
					(justify left bottom)
					(hide yes)
				)
			)
			(property "Footprint" "antmicro-footprints:C_0603_1608Metric"
				(at 20.32 -12.7 0)
				(effects
					(font
						(size 1.27 1.27)
						(thickness 0.15)
					)
					(justify left bottom)
					(hide yes)
				)
			)
			(property "Datasheet" "https://www.murata.com/products/productdetail?partno=GRM188R60J226MEA0%23"
				(at 20.32 -15.24 0)
				(effects
					(font
						(size 1.27 1.27)
						(thickness 0.15)
					)
					(justify left bottom)
					(hide yes)
				)
			)
			(property "Description" "SMD Multilayer Ceramic Capacitor, 22 µF, 6.3 V, 0603 [1608 Metric], ± 20%, X5R, GRM Series"
				(at 20.32 -33.02 0)
				(effects
					(font
						(size 1.27 1.27)
					)
					(justify left bottom)
					(hide yes)
				)
			)
			(property "MPN" "GRM188R60J226MEA0D"
				(at 20.32 -17.78 0)
				(effects
					(font
						(size 1.27 1.27)
						(thickness 0.15)
					)
					(justify left bottom)
					(hide yes)
				)
			)
			(property "Manufacturer" "Murata"
				(at 20.32 -20.32 0)
				(effects
					(font
						(size 1.27 1.27)
						(thickness 0.15)
					)
					(justify left bottom)
					(hide yes)
				)
			)
			(property "License" "Apache-2.0"
				(at 20.32 -22.86 0)
				(effects
					(font
						(size 1.27 1.27)
						(thickness 0.15)
					)
					(justify left bottom)
					(hide yes)
				)
			)
			(property "Author" "Antmicro"
				(at 20.32 -25.4 0)
				(effects
					(font
						(size 1.27 1.27)
						(thickness 0.15)
					)
					(justify left bottom)
					(hide yes)
				)
			)
			(property "Val" "22u"
				(at 20.32 -7.62 0)
				(effects
					(font
						(size 1.27 1.27)
						(thickness 0.15)
					)
					(justify left bottom)
				)
			)
			(property "Voltage" ""
				(at 20.32 -27.94 0)
				(effects
					(font
						(size 1.27 1.27)
					)
					(justify left bottom)
					(hide yes)
				)
			)
			(property "Dielectric" ""
				(at 20.32 -30.48 0)
				(effects
					(font
						(size 1.27 1.27)
					)
					(justify left bottom)
					(hide yes)
				)
			)
			(property "ki_keywords" "0603, SMT, CAPACITOR, PASSIVE, CERAMIC, MLCC"
				(at 0 0 0)
				(effects
					(font
						(size 1.27 1.27)
					)
					(hide yes)
				)
			)
			(symbol "C_22u_0603_0_1"
				(polyline
					(pts
						(xy 2.032 -1.524) (xy 2.032 1.524)
					)
					(stroke
						(width 0.3048)
						(type default)
					)
					(fill
						(type none)
					)
				)
				(polyline
					(pts
						(xy 3.048 -1.524) (xy 3.048 1.524)
					)
					(stroke
						(width 0.3302)
						(type default)
					)
					(fill
						(type none)
					)
				)
			)
			(symbol "C_22u_0603_1_1"
				(pin passive line
					(at 0 0 0)
					(length 2.032)
					(name "~"
						(effects
							(font
								(size 1.27 1.27)
							)
						)
					)
					(number "1"
						(effects
							(font
								(size 1.27 1.27)
							)
						)
					)
				)
				(pin passive line
					(at 5.08 0 180)
					(length 2.032)
					(name "~"
						(effects
							(font
								(size 1.27 1.27)
							)
						)
					)
					(number "2"
						(effects
							(font
								(size 1.27 1.27)
							)
						)
					)
				)
			)
		)
	(symbol "antmicroCapacitorsmisc:C_100n_0201"
			(pin_numbers
				(hide yes)
			)
			(pin_names
				(hide yes)
			)
			(exclude_from_sim no)
			(in_bom yes)
			(on_board yes)
			(property "Reference" "C"
				(at 20.32 -5.08 0)
				(effects
					(font
						(size 1.27 1.27)
						(thickness 0.15)
					)
					(justify left bottom)
				)
			)
			(property "Value" "C_100n_0201"
				(at 20.32 -10.16 0)
				(effects
					(font
						(size 1.27 1.27)
						(thickness 0.15)
					)
					(justify left bottom)
					(hide yes)
				)
			)
			(property "Footprint" "antmicro-footprints:C_0201"
				(at 20.32 -12.7 0)
				(effects
					(font
						(size 1.27 1.27)
						(thickness 0.15)
					)
					(justify left bottom)
					(hide yes)
				)
			)
			(property "Datasheet" "https://www.yageo.com/en/Chart/Download/pdf/CC0201KRX6S5BB104"
				(at 20.32 -15.24 0)
				(effects
					(font
						(size 1.27 1.27)
						(thickness 0.15)
					)
					(justify left bottom)
					(hide yes)
				)
			)
			(property "Description" "SMD Multilayer Ceramic Capacitor, 0.1 µF, 6.3 V, 0201 [0603 Metric], ± 10%, X6S, CC Series"
				(at 20.32 -33.02 0)
				(effects
					(font
						(size 1.27 1.27)
					)
					(justify left bottom)
					(hide yes)
				)
			)
			(property "MPN" "CC0201KRX6S5BB104"
				(at 20.32 -17.78 0)
				(effects
					(font
						(size 1.27 1.27)
						(thickness 0.15)
					)
					(justify left bottom)
					(hide yes)
				)
			)
			(property "Manufacturer" "YAGEO"
				(at 20.32 -20.32 0)
				(effects
					(font
						(size 1.27 1.27)
						(thickness 0.15)
					)
					(justify left bottom)
					(hide yes)
				)
			)
			(property "License" "Apache-2.0"
				(at 20.32 -22.86 0)
				(effects
					(font
						(size 1.27 1.27)
						(thickness 0.15)
					)
					(justify left bottom)
					(hide yes)
				)
			)
			(property "Author" "Antmicro"
				(at 20.32 -25.4 0)
				(effects
					(font
						(size 1.27 1.27)
						(thickness 0.15)
					)
					(justify left bottom)
					(hide yes)
				)
			)
			(property "Val" "100n"
				(at 20.32 -7.62 0)
				(effects
					(font
						(size 1.27 1.27)
						(thickness 0.15)
					)
					(justify left bottom)
				)
			)
			(property "Voltage" ""
				(at 20.32 -27.94 0)
				(effects
					(font
						(size 1.27 1.27)
					)
					(justify left bottom)
					(hide yes)
				)
			)
			(property "Dielectric" ""
				(at 20.32 -30.48 0)
				(effects
					(font
						(size 1.27 1.27)
					)
					(justify left bottom)
					(hide yes)
				)
			)
			(property "Public" "False"
				(at 20.32 -33.02 0)
				(effects
					(font
						(size 1.27 1.27)
					)
					(justify left bottom)
					(hide yes)
				)
			)
			(property "ki_keywords" "0201, SMT, CAPACITOR, PASSIVE, MLCC, CERAMIC"
				(at 0 0 0)
				(effects
					(font
						(size 1.27 1.27)
					)
					(hide yes)
				)
			)
			(symbol "C_100n_0201_0_1"
				(polyline
					(pts
						(xy 2.032 -1.524) (xy 2.032 1.524)
					)
					(stroke
						(width 0.3048)
						(type default)
					)
					(fill
						(type none)
					)
				)
				(polyline
					(pts
						(xy 3.048 -1.524) (xy 3.048 1.524)
					)
					(stroke
						(width 0.3302)
						(type default)
					)
					(fill
						(type none)
					)
				)
			)
			(symbol "C_100n_0201_1_1"
				(pin passive line
					(at 0 0 0)
					(length 2.032)
					(name "~"
						(effects
							(font
								(size 1.27 1.27)
							)
						)
					)
					(number "1"
						(effects
							(font
								(size 1.27 1.27)
							)
						)
					)
				)
				(pin passive line
					(at 5.08 0 180)
					(length 2.032)
					(name "~"
						(effects
							(font
								(size 1.27 1.27)
							)
						)
					)
					(number "2"
						(effects
							(font
								(size 1.27 1.27)
							)
						)
					)
				)
			)
		)
	(symbol "antmicroCapacitorspol:C_Pol_33u_4V_KYOCERA-AVX-F98-0603"
			(pin_numbers
				(hide yes)
			)
			(pin_names
				(hide yes)
			)
			(exclude_from_sim no)
			(in_bom yes)
			(on_board yes)
			(property "Reference" "C"
				(at 13.97 0 0)
				(effects
					(font
						(size 1.27 1.27)
						(thickness 0.15)
					)
					(justify left bottom)
				)
			)
			(property "Value" "C_Pol_33u_4V_KYOCERA-AVX-F98-0603"
				(at 13.97 -2.54 0)
				(effects
					(font
						(size 1.27 1.27)
						(thickness 0.15)
					)
					(justify left bottom)
					(hide yes)
				)
			)
			(property "Footprint" "antmicro-footprints:C_Pol_0603_1608Metric"
				(at 13.97 -7.62 0)
				(effects
					(font
						(size 1.27 1.27)
						(thickness 0.15)
					)
					(justify left bottom)
					(hide yes)
				)
			)
			(property "Datasheet" "https://spicat.kyocera-avx.com/product/tan/chartview/F980G336MMA/"
				(at 13.97 -10.16 0)
				(effects
					(font
						(size 1.27 1.27)
						(thickness 0.15)
					)
					(justify left bottom)
					(hide yes)
				)
			)
			(property "Description" "Surface Mount Tantalum Capacitor, 33 µF, 4 V, 0603 [1608 Metric], ± 20%, 4 ohm, M"
				(at 13.97 -25.4 0)
				(effects
					(font
						(size 1.27 1.27)
					)
					(justify left bottom)
					(hide yes)
				)
			)
			(property "Val" "33u"
				(at 13.97 -5.08 0)
				(effects
					(font
						(size 1.27 1.27)
						(thickness 0.15)
					)
					(justify left bottom)
				)
			)
			(property "MPN" "F980G336MMA"
				(at 13.97 -12.7 0)
				(effects
					(font
						(size 1.27 1.27)
						(thickness 0.15)
					)
					(justify left bottom)
					(hide yes)
				)
			)
			(property "Manufacturer" "KYOCERA AVX"
				(at 13.97 -15.24 0)
				(effects
					(font
						(size 1.27 1.27)
						(thickness 0.15)
					)
					(justify left bottom)
					(hide yes)
				)
			)
			(property "License" "Apache-2.0"
				(at 13.97 -17.78 0)
				(effects
					(font
						(size 1.27 1.27)
						(thickness 0.15)
					)
					(justify left bottom)
					(hide yes)
				)
			)
			(property "Author" "Antmicro"
				(at 13.97 -20.32 0)
				(effects
					(font
						(size 1.27 1.27)
						(thickness 0.15)
					)
					(justify left bottom)
					(hide yes)
				)
			)
			(property "Voltage" "4V"
				(at 13.97 -22.86 0)
				(effects
					(font
						(size 1.27 1.27)
					)
					(justify left bottom)
					(hide yes)
				)
			)
			(property "Dielectric" "template_dielectric"
				(at 13.97 -25.4 0)
				(effects
					(font
						(size 1.27 1.27)
					)
					(justify left bottom)
					(hide yes)
				)
			)
			(property "ki_keywords" "0603, SMT, CAPACITOR, PASSIVE, TANTALUM"
				(at 0 0 0)
				(effects
					(font
						(size 1.27 1.27)
					)
					(hide yes)
				)
			)
			(symbol "C_Pol_33u_4V_KYOCERA-AVX-F98-0603_0_1"
				(polyline
					(pts
						(xy 0.9652 1.27) (xy 0.9652 1.778)
					)
					(stroke
						(width 0)
						(type default)
					)
					(fill
						(type none)
					)
				)
				(polyline
					(pts
						(xy 1.2192 1.524) (xy 0.7112 1.524)
					)
					(stroke
						(width 0)
						(type default)
					)
					(fill
						(type none)
					)
				)
				(rectangle
					(start 1.905 -1.524)
					(end 2.286 1.524)
					(stroke
						(width 0)
						(type default)
					)
					(fill
						(type none)
					)
				)
				(rectangle
					(start 2.921 -1.524)
					(end 3.302 1.524)
					(stroke
						(width 0)
						(type default)
					)
					(fill
						(type outline)
					)
				)
			)
			(symbol "C_Pol_33u_4V_KYOCERA-AVX-F98-0603_1_1"
				(pin passive line
					(at 0 0 0)
					(length 1.8542)
					(name "~"
						(effects
							(font
								(size 1.27 1.27)
							)
						)
					)
					(number "1"
						(effects
							(font
								(size 1.27 1.27)
							)
						)
					)
				)
				(pin passive line
					(at 5.08 0 180)
					(length 1.8542)
					(name "~"
						(effects
							(font
								(size 1.27 1.27)
							)
						)
					)
					(number "2"
						(effects
							(font
								(size 1.27 1.27)
							)
						)
					)
				)
			)
		)
	(symbol "antmicroCoaxialConnectorsRF:Conn_BNC_031-70526-21"
			(pin_names
				(hide yes)
			)
			(exclude_from_sim no)
			(in_bom yes)
			(on_board yes)
			(property "Reference" "J"
				(at 20.32 -5.08 0)
				(effects
					(font
						(size 1.27 1.27)
						(thickness 0.15)
					)
					(justify left bottom)
				)
			)
			(property "Value" "Conn_BNC_031-70526-21"
				(at 20.32 -7.62 0)
				(effects
					(font
						(size 1.27 1.27)
						(thickness 0.15)
					)
					(justify left bottom)
					(hide yes)
				)
			)
			(property "Footprint" "antmicro-footprints:Conn_BNC_031-70526-21"
				(at 20.32 -10.16 0)
				(effects
					(font
						(size 1.27 1.27)
						(thickness 0.15)
					)
					(justify left bottom)
					(hide yes)
				)
			)
			(property "Datasheet" "https://www.farnell.com/cad/2305565.pdf?_ga=2.190633003.1014497200.1574067480-156563690.1566371002&_gac=1.57062104.1572875319.Cj0KCQiAtf_tBRDtARIsAIbAKe0A1M5y_jdFCiNLNrHM5L2GjmDvn_4qnRvhHAD9jBdL9AmoMNThLCoaAjhJEALw_wcB"
				(at 20.32 -12.7 0)
				(effects
					(font
						(size 1.27 1.27)
						(thickness 0.15)
					)
					(justify left bottom)
					(hide yes)
				)
			)
			(property "Description" "RF / Coaxial Connector, BNC Coaxial, Straight Bulkhead Jack, Board Edge / End Launch, 75 ohm"
				(at 20.32 -25.4 0)
				(effects
					(font
						(size 1.27 1.27)
					)
					(justify left bottom)
					(hide yes)
				)
			)
			(property "MPN" "031-70526-21"
				(at 20.32 -15.24 0)
				(effects
					(font
						(size 1.27 1.27)
						(thickness 0.15)
					)
					(justify left bottom)
				)
			)
			(property "Manufacturer" "Amphenol"
				(at 20.32 -17.78 0)
				(effects
					(font
						(size 1.27 1.27)
						(thickness 0.15)
					)
					(justify left bottom)
					(hide yes)
				)
			)
			(property "Author" "Antmicro"
				(at 20.32 -20.32 0)
				(effects
					(font
						(size 1.27 1.27)
						(thickness 0.15)
					)
					(justify left bottom)
					(hide yes)
				)
			)
			(property "License" "Apache-2.0"
				(at 20.32 -22.86 0)
				(effects
					(font
						(size 1.27 1.27)
						(thickness 0.15)
					)
					(justify left bottom)
					(hide yes)
				)
			)
			(property "ki_keywords" "HORIZONTAL, BULKHEAD, RF, CONNECTOR"
				(at 0 0 0)
				(effects
					(font
						(size 1.27 1.27)
					)
					(hide yes)
				)
			)
			(property "ki_fp_filters" "*BNC* *SMA* *SMB* *SMC* *Cinch*"
				(at 0 0 0)
				(effects
					(font
						(size 1.27 1.27)
					)
					(hide yes)
				)
			)
			(symbol "Conn_BNC_031-70526-21_1_1"
				(polyline
					(pts
						(xy 2.54 0) (xy 4.572 0)
					)
					(stroke
						(width 0.254)
						(type default)
					)
					(fill
						(type none)
					)
				)
				(arc
					(start 3.302 0.508)
					(mid 5.302 1.8083)
					(end 6.858 0)
					(stroke
						(width 0.254)
						(type default)
					)
					(fill
						(type none)
					)
				)
				(arc
					(start 6.858 0)
					(mid 5.302 -1.808)
					(end 3.302 -0.508)
					(stroke
						(width 0.254)
						(type default)
					)
					(fill
						(type none)
					)
				)
				(circle
					(center 5.08 0)
					(radius 0.508)
					(stroke
						(width 0.254)
						(type default)
					)
					(fill
						(type none)
					)
				)
				(polyline
					(pts
						(xy 5.08 -2.54) (xy 5.08 -1.778)
					)
					(stroke
						(width 0.254)
						(type default)
					)
					(fill
						(type none)
					)
				)
				(pin passive line
					(at 0 0 0)
					(length 2.54)
					(name "1"
						(effects
							(font
								(size 1.27 1.27)
							)
						)
					)
					(number "1"
						(effects
							(font
								(size 1.27 1.27)
							)
						)
					)
				)
				(pin passive line
					(at 5.08 -5.08 90)
					(length 2.54)
					(name "2"
						(effects
							(font
								(size 1.27 1.27)
							)
						)
					)
					(number "2"
						(effects
							(font
								(size 1.27 1.27)
							)
						)
					)
				)
			)
		)
	(symbol "antmicroDCDCConverters:AP62301_TSOT"
			(exclude_from_sim no)
			(in_bom yes)
			(on_board yes)
			(property "Reference" "U"
				(at 35.56 -2.54 0)
				(effects
					(font
						(size 1.27 1.27)
						(thickness 0.15)
					)
					(justify left bottom)
				)
			)
			(property "Value" "AP62301_TSOT"
				(at 35.56 -7.62 0)
				(effects
					(font
						(size 1.27 1.27)
						(thickness 0.15)
					)
					(justify left bottom)
					(hide yes)
				)
			)
			(property "Footprint" "antmicro-footprints:TSOT23-6"
				(at 35.56 -10.16 0)
				(effects
					(font
						(size 1.27 1.27)
						(thickness 0.15)
					)
					(justify left bottom)
					(hide yes)
				)
			)
			(property "Datasheet" "https://www.diodes.com/assets/Datasheets/AP62300_AP62301_AP62300T.pdf"
				(at 35.56 -12.7 0)
				(effects
					(font
						(size 1.27 1.27)
						(thickness 0.15)
					)
					(justify left bottom)
					(hide yes)
				)
			)
			(property "Description" "DC-DC Switching Synchronous Buck Regulator, Adjustable, 4.2V-18Vin, 0.8V-7V/3A out, TSOT-26-6"
				(at 35.56 -22.86 0)
				(effects
					(font
						(size 1.27 1.27)
					)
					(justify left bottom)
					(hide yes)
				)
			)
			(property "MPN" "AP62301WU-7"
				(at 35.56 -5.08 0)
				(effects
					(font
						(size 1.27 1.27)
						(thickness 0.15)
					)
					(justify left bottom)
				)
			)
			(property "Manufacturer" "Diodes Incorporated"
				(at 35.56 -15.24 0)
				(effects
					(font
						(size 1.27 1.27)
						(thickness 0.15)
					)
					(justify left bottom)
					(hide yes)
				)
			)
			(property "Author" "Antmicro"
				(at 35.56 -17.78 0)
				(effects
					(font
						(size 1.27 1.27)
						(thickness 0.15)
					)
					(justify left bottom)
					(hide yes)
				)
			)
			(property "License" "Apache-2.0"
				(at 35.56 -20.32 0)
				(effects
					(font
						(size 1.27 1.27)
						(thickness 0.15)
					)
					(justify left bottom)
					(hide yes)
				)
			)
			(property "ki_keywords" "SMT, PMIC, IC, VOLTAGE"
				(at 0 0 0)
				(effects
					(font
						(size 1.27 1.27)
					)
					(hide yes)
				)
			)
			(symbol "AP62301_TSOT_1_1"
				(rectangle
					(start 2.54 2.54)
					(end 17.78 -12.7)
					(stroke
						(width 0.254)
						(type default)
					)
					(fill
						(type background)
					)
				)
				(pin power_in line
					(at 0 0 0)
					(length 2.54)
					(name "VIN"
						(effects
							(font
								(size 1.27 1.27)
							)
						)
					)
					(number "3"
						(effects
							(font
								(size 1.27 1.27)
							)
						)
					)
				)
				(pin input line
					(at 0 -5.08 0)
					(length 2.54)
					(name "EN"
						(effects
							(font
								(size 1.27 1.27)
							)
						)
					)
					(number "5"
						(effects
							(font
								(size 1.27 1.27)
							)
						)
					)
				)
				(pin power_in line
					(at 0 -10.16 0)
					(length 2.54)
					(name "GND"
						(effects
							(font
								(size 1.27 1.27)
							)
						)
					)
					(number "1"
						(effects
							(font
								(size 1.27 1.27)
							)
						)
					)
				)
				(pin power_out line
					(at 20.32 0 180)
					(length 2.54)
					(name "SW"
						(effects
							(font
								(size 1.27 1.27)
							)
						)
					)
					(number "2"
						(effects
							(font
								(size 1.27 1.27)
							)
						)
					)
				)
				(pin output line
					(at 20.32 -5.08 180)
					(length 2.54)
					(name "BST"
						(effects
							(font
								(size 1.27 1.27)
							)
						)
					)
					(number "6"
						(effects
							(font
								(size 1.27 1.27)
							)
						)
					)
				)
				(pin input line
					(at 20.32 -10.16 180)
					(length 2.54)
					(name "FB"
						(effects
							(font
								(size 1.27 1.27)
							)
						)
					)
					(number "4"
						(effects
							(font
								(size 1.27 1.27)
							)
						)
					)
				)
			)
		)
	(symbol "antmicroFCCConnectors:Conn_FFC_WE_68715014522"
			(exclude_from_sim no)
			(in_bom yes)
			(on_board yes)
			(property "Reference" "J"
				(at 19.05 -5.08 0)
				(effects
					(font
						(size 1.27 1.27)
						(thickness 0.15)
					)
					(justify left bottom)
				)
			)
			(property "Value" "Conn_FFC_WE_68715014522"
				(at 19.05 -7.62 0)
				(effects
					(font
						(size 1.27 1.27)
						(thickness 0.15)
					)
					(justify left bottom)
					(hide yes)
				)
			)
			(property "Footprint" "antmicro-footprints:Conn_FFC_WE_68715014x22"
				(at 19.05 -10.16 0)
				(effects
					(font
						(size 1.27 1.27)
						(thickness 0.15)
					)
					(justify left bottom)
					(hide yes)
				)
			)
			(property "Datasheet" "https://www.we-online.com/components/products/datasheet/68715014522.pdf"
				(at 19.05 -12.7 0)
				(effects
					(font
						(size 1.27 1.27)
						(thickness 0.15)
					)
					(justify left bottom)
					(hide yes)
				)
			)
			(property "Description" "FFC connector"
				(at 19.05 -25.4 0)
				(effects
					(font
						(size 1.27 1.27)
					)
					(justify left bottom)
					(hide yes)
				)
			)
			(property "MPN" "68715014522"
				(at 19.05 -15.24 0)
				(effects
					(font
						(size 1.27 1.27)
						(thickness 0.15)
					)
					(justify left bottom)
				)
			)
			(property "Manufacturer" "Würth Elektronik"
				(at 19.05 -17.78 0)
				(effects
					(font
						(size 1.27 1.27)
						(thickness 0.15)
					)
					(justify left bottom)
					(hide yes)
				)
			)
			(property "Author" "Antmicro"
				(at 19.05 -20.32 0)
				(effects
					(font
						(size 1.27 1.27)
						(thickness 0.15)
					)
					(justify left bottom)
					(hide yes)
				)
			)
			(property "License" "Apache-2.0"
				(at 19.05 -22.86 0)
				(effects
					(font
						(size 1.27 1.27)
						(thickness 0.15)
					)
					(justify left bottom)
					(hide yes)
				)
			)
			(property "ki_keywords" "CONNECTOR"
				(at 0 0 0)
				(effects
					(font
						(size 1.27 1.27)
					)
					(hide yes)
				)
			)
			(symbol "Conn_FFC_WE_68715014522_1_1"
				(rectangle
					(start 3.81 1.27)
					(end 7.62 -132.08)
					(stroke
						(width 0.254)
						(type default)
					)
					(fill
						(type background)
					)
				)
				(rectangle
					(start 3.81 0.127)
					(end 5.08 -0.127)
					(stroke
						(width 0.254)
						(type default)
					)
					(fill
						(type background)
					)
				)
				(rectangle
					(start 3.81 -2.413)
					(end 5.08 -2.667)
					(stroke
						(width 0.254)
						(type default)
					)
					(fill
						(type background)
					)
				)
				(rectangle
					(start 3.81 -4.953)
					(end 5.08 -5.207)
					(stroke
						(width 0.254)
						(type default)
					)
					(fill
						(type background)
					)
				)
				(rectangle
					(start 3.81 -7.493)
					(end 5.08 -7.747)
					(stroke
						(width 0.254)
						(type default)
					)
					(fill
						(type background)
					)
				)
				(rectangle
					(start 3.81 -10.033)
					(end 5.08 -10.287)
					(stroke
						(width 0.254)
						(type default)
					)
					(fill
						(type background)
					)
				)
				(rectangle
					(start 3.81 -12.573)
					(end 5.08 -12.827)
					(stroke
						(width 0.254)
						(type default)
					)
					(fill
						(type background)
					)
				)
				(rectangle
					(start 3.81 -15.113)
					(end 5.08 -15.367)
					(stroke
						(width 0.254)
						(type default)
					)
					(fill
						(type background)
					)
				)
				(rectangle
					(start 3.81 -17.653)
					(end 5.08 -17.907)
					(stroke
						(width 0.254)
						(type default)
					)
					(fill
						(type background)
					)
				)
				(rectangle
					(start 3.81 -20.193)
					(end 5.08 -20.447)
					(stroke
						(width 0.254)
						(type default)
					)
					(fill
						(type background)
					)
				)
				(rectangle
					(start 3.81 -22.733)
					(end 5.08 -22.987)
					(stroke
						(width 0.254)
						(type default)
					)
					(fill
						(type background)
					)
				)
				(rectangle
					(start 3.81 -25.273)
					(end 5.08 -25.527)
					(stroke
						(width 0.254)
						(type default)
					)
					(fill
						(type background)
					)
				)
				(rectangle
					(start 3.81 -27.813)
					(end 5.08 -28.067)
					(stroke
						(width 0.254)
						(type default)
					)
					(fill
						(type background)
					)
				)
				(rectangle
					(start 3.81 -30.353)
					(end 5.08 -30.607)
					(stroke
						(width 0.254)
						(type default)
					)
					(fill
						(type background)
					)
				)
				(rectangle
					(start 3.81 -32.893)
					(end 5.08 -33.147)
					(stroke
						(width 0.254)
						(type default)
					)
					(fill
						(type background)
					)
				)
				(rectangle
					(start 3.81 -35.433)
					(end 5.08 -35.687)
					(stroke
						(width 0.254)
						(type default)
					)
					(fill
						(type background)
					)
				)
				(rectangle
					(start 3.81 -37.973)
					(end 5.08 -38.227)
					(stroke
						(width 0.254)
						(type default)
					)
					(fill
						(type background)
					)
				)
				(rectangle
					(start 3.81 -40.513)
					(end 5.08 -40.767)
					(stroke
						(width 0.254)
						(type default)
					)
					(fill
						(type background)
					)
				)
				(rectangle
					(start 3.81 -43.053)
					(end 5.08 -43.307)
					(stroke
						(width 0.254)
						(type default)
					)
					(fill
						(type background)
					)
				)
				(rectangle
					(start 3.81 -45.593)
					(end 5.08 -45.847)
					(stroke
						(width 0.254)
						(type default)
					)
					(fill
						(type background)
					)
				)
				(rectangle
					(start 3.81 -48.133)
					(end 5.08 -48.387)
					(stroke
						(width 0.254)
						(type default)
					)
					(fill
						(type background)
					)
				)
				(rectangle
					(start 3.81 -50.673)
					(end 5.08 -50.927)
					(stroke
						(width 0.254)
						(type default)
					)
					(fill
						(type background)
					)
				)
				(rectangle
					(start 3.81 -53.213)
					(end 5.08 -53.467)
					(stroke
						(width 0.254)
						(type default)
					)
					(fill
						(type background)
					)
				)
				(rectangle
					(start 3.81 -55.753)
					(end 5.08 -56.007)
					(stroke
						(width 0.254)
						(type default)
					)
					(fill
						(type background)
					)
				)
				(rectangle
					(start 3.81 -58.293)
					(end 5.08 -58.547)
					(stroke
						(width 0.254)
						(type default)
					)
					(fill
						(type background)
					)
				)
				(rectangle
					(start 3.81 -60.833)
					(end 5.08 -61.087)
					(stroke
						(width 0.254)
						(type default)
					)
					(fill
						(type background)
					)
				)
				(rectangle
					(start 3.81 -63.373)
					(end 5.08 -63.627)
					(stroke
						(width 0.254)
						(type default)
					)
					(fill
						(type background)
					)
				)
				(rectangle
					(start 3.81 -65.913)
					(end 5.08 -66.167)
					(stroke
						(width 0.254)
						(type default)
					)
					(fill
						(type background)
					)
				)
				(rectangle
					(start 3.81 -68.453)
					(end 5.08 -68.707)
					(stroke
						(width 0.254)
						(type default)
					)
					(fill
						(type background)
					)
				)
				(rectangle
					(start 3.81 -70.993)
					(end 5.08 -71.247)
					(stroke
						(width 0.254)
						(type default)
					)
					(fill
						(type background)
					)
				)
				(rectangle
					(start 3.81 -73.533)
					(end 5.08 -73.787)
					(stroke
						(width 0.254)
						(type default)
					)
					(fill
						(type background)
					)
				)
				(rectangle
					(start 3.81 -76.073)
					(end 5.08 -76.327)
					(stroke
						(width 0.254)
						(type default)
					)
					(fill
						(type background)
					)
				)
				(rectangle
					(start 3.81 -78.613)
					(end 5.08 -78.867)
					(stroke
						(width 0.254)
						(type default)
					)
					(fill
						(type background)
					)
				)
				(rectangle
					(start 3.81 -81.153)
					(end 5.08 -81.407)
					(stroke
						(width 0.254)
						(type default)
					)
					(fill
						(type background)
					)
				)
				(rectangle
					(start 3.81 -83.693)
					(end 5.08 -83.947)
					(stroke
						(width 0.254)
						(type default)
					)
					(fill
						(type background)
					)
				)
				(rectangle
					(start 3.81 -86.233)
					(end 5.08 -86.487)
					(stroke
						(width 0.254)
						(type default)
					)
					(fill
						(type background)
					)
				)
				(rectangle
					(start 3.81 -88.773)
					(end 5.08 -89.027)
					(stroke
						(width 0.254)
						(type default)
					)
					(fill
						(type background)
					)
				)
				(rectangle
					(start 3.81 -91.313)
					(end 5.08 -91.567)
					(stroke
						(width 0.254)
						(type default)
					)
					(fill
						(type background)
					)
				)
				(rectangle
					(start 3.81 -93.853)
					(end 5.08 -94.107)
					(stroke
						(width 0.254)
						(type default)
					)
					(fill
						(type background)
					)
				)
				(rectangle
					(start 3.81 -96.393)
					(end 5.08 -96.647)
					(stroke
						(width 0.254)
						(type default)
					)
					(fill
						(type background)
					)
				)
				(rectangle
					(start 3.81 -98.933)
					(end 5.08 -99.187)
					(stroke
						(width 0.254)
						(type default)
					)
					(fill
						(type background)
					)
				)
				(rectangle
					(start 3.81 -101.473)
					(end 5.08 -101.727)
					(stroke
						(width 0.254)
						(type default)
					)
					(fill
						(type background)
					)
				)
				(rectangle
					(start 3.81 -104.013)
					(end 5.08 -104.267)
					(stroke
						(width 0.254)
						(type default)
					)
					(fill
						(type background)
					)
				)
				(rectangle
					(start 3.81 -106.553)
					(end 5.08 -106.807)
					(stroke
						(width 0.254)
						(type default)
					)
					(fill
						(type background)
					)
				)
				(rectangle
					(start 3.81 -109.093)
					(end 5.08 -109.347)
					(stroke
						(width 0.254)
						(type default)
					)
					(fill
						(type background)
					)
				)
				(rectangle
					(start 3.81 -111.633)
					(end 5.08 -111.887)
					(stroke
						(width 0.254)
						(type default)
					)
					(fill
						(type background)
					)
				)
				(rectangle
					(start 3.81 -114.173)
					(end 5.08 -114.427)
					(stroke
						(width 0.254)
						(type default)
					)
					(fill
						(type background)
					)
				)
				(rectangle
					(start 3.81 -116.713)
					(end 5.08 -116.967)
					(stroke
						(width 0.254)
						(type default)
					)
					(fill
						(type background)
					)
				)
				(rectangle
					(start 3.81 -119.253)
					(end 5.08 -119.507)
					(stroke
						(width 0.254)
						(type default)
					)
					(fill
						(type background)
					)
				)
				(rectangle
					(start 3.81 -121.793)
					(end 5.08 -122.047)
					(stroke
						(width 0.254)
						(type default)
					)
					(fill
						(type background)
					)
				)
				(rectangle
					(start 3.81 -124.333)
					(end 5.08 -124.587)
					(stroke
						(width 0.254)
						(type default)
					)
					(fill
						(type background)
					)
				)
				(pin passive line
					(at 0 0 0)
					(length 3.81)
					(name "~"
						(effects
							(font
								(size 1.27 1.27)
							)
						)
					)
					(number "1"
						(effects
							(font
								(size 1.27 1.27)
							)
						)
					)
				)
				(pin passive line
					(at 0 -2.54 0)
					(length 3.81)
					(name "~"
						(effects
							(font
								(size 1.27 1.27)
							)
						)
					)
					(number "2"
						(effects
							(font
								(size 1.27 1.27)
							)
						)
					)
				)
				(pin passive line
					(at 0 -5.08 0)
					(length 3.81)
					(name "~"
						(effects
							(font
								(size 1.27 1.27)
							)
						)
					)
					(number "3"
						(effects
							(font
								(size 1.27 1.27)
							)
						)
					)
				)
				(pin passive line
					(at 0 -7.62 0)
					(length 3.81)
					(name "~"
						(effects
							(font
								(size 1.27 1.27)
							)
						)
					)
					(number "4"
						(effects
							(font
								(size 1.27 1.27)
							)
						)
					)
				)
				(pin passive line
					(at 0 -10.16 0)
					(length 3.81)
					(name "~"
						(effects
							(font
								(size 1.27 1.27)
							)
						)
					)
					(number "5"
						(effects
							(font
								(size 1.27 1.27)
							)
						)
					)
				)
				(pin passive line
					(at 0 -12.7 0)
					(length 3.81)
					(name "~"
						(effects
							(font
								(size 1.27 1.27)
							)
						)
					)
					(number "6"
						(effects
							(font
								(size 1.27 1.27)
							)
						)
					)
				)
				(pin passive line
					(at 0 -15.24 0)
					(length 3.81)
					(name "~"
						(effects
							(font
								(size 1.27 1.27)
							)
						)
					)
					(number "7"
						(effects
							(font
								(size 1.27 1.27)
							)
						)
					)
				)
				(pin passive line
					(at 0 -17.78 0)
					(length 3.81)
					(name "~"
						(effects
							(font
								(size 1.27 1.27)
							)
						)
					)
					(number "8"
						(effects
							(font
								(size 1.27 1.27)
							)
						)
					)
				)
				(pin passive line
					(at 0 -20.32 0)
					(length 3.81)
					(name "~"
						(effects
							(font
								(size 1.27 1.27)
							)
						)
					)
					(number "9"
						(effects
							(font
								(size 1.27 1.27)
							)
						)
					)
				)
				(pin passive line
					(at 0 -22.86 0)
					(length 3.81)
					(name "~"
						(effects
							(font
								(size 1.27 1.27)
							)
						)
					)
					(number "10"
						(effects
							(font
								(size 1.27 1.27)
							)
						)
					)
				)
				(pin passive line
					(at 0 -25.4 0)
					(length 3.81)
					(name "~"
						(effects
							(font
								(size 1.27 1.27)
							)
						)
					)
					(number "11"
						(effects
							(font
								(size 1.27 1.27)
							)
						)
					)
				)
				(pin passive line
					(at 0 -27.94 0)
					(length 3.81)
					(name "~"
						(effects
							(font
								(size 1.27 1.27)
							)
						)
					)
					(number "12"
						(effects
							(font
								(size 1.27 1.27)
							)
						)
					)
				)
				(pin passive line
					(at 0 -30.48 0)
					(length 3.81)
					(name "~"
						(effects
							(font
								(size 1.27 1.27)
							)
						)
					)
					(number "13"
						(effects
							(font
								(size 1.27 1.27)
							)
						)
					)
				)
				(pin passive line
					(at 0 -33.02 0)
					(length 3.81)
					(name "~"
						(effects
							(font
								(size 1.27 1.27)
							)
						)
					)
					(number "14"
						(effects
							(font
								(size 1.27 1.27)
							)
						)
					)
				)
				(pin passive line
					(at 0 -35.56 0)
					(length 3.81)
					(name "~"
						(effects
							(font
								(size 1.27 1.27)
							)
						)
					)
					(number "15"
						(effects
							(font
								(size 1.27 1.27)
							)
						)
					)
				)
				(pin passive line
					(at 0 -38.1 0)
					(length 3.81)
					(name "~"
						(effects
							(font
								(size 1.27 1.27)
							)
						)
					)
					(number "16"
						(effects
							(font
								(size 1.27 1.27)
							)
						)
					)
				)
				(pin passive line
					(at 0 -40.64 0)
					(length 3.81)
					(name "~"
						(effects
							(font
								(size 1.27 1.27)
							)
						)
					)
					(number "17"
						(effects
							(font
								(size 1.27 1.27)
							)
						)
					)
				)
				(pin passive line
					(at 0 -43.18 0)
					(length 3.81)
					(name "~"
						(effects
							(font
								(size 1.27 1.27)
							)
						)
					)
					(number "18"
						(effects
							(font
								(size 1.27 1.27)
							)
						)
					)
				)
				(pin passive line
					(at 0 -45.72 0)
					(length 3.81)
					(name "~"
						(effects
							(font
								(size 1.27 1.27)
							)
						)
					)
					(number "19"
						(effects
							(font
								(size 1.27 1.27)
							)
						)
					)
				)
				(pin passive line
					(at 0 -48.26 0)
					(length 3.81)
					(name "~"
						(effects
							(font
								(size 1.27 1.27)
							)
						)
					)
					(number "20"
						(effects
							(font
								(size 1.27 1.27)
							)
						)
					)
				)
				(pin passive line
					(at 0 -50.8 0)
					(length 3.81)
					(name "~"
						(effects
							(font
								(size 1.27 1.27)
							)
						)
					)
					(number "21"
						(effects
							(font
								(size 1.27 1.27)
							)
						)
					)
				)
				(pin passive line
					(at 0 -53.34 0)
					(length 3.81)
					(name "~"
						(effects
							(font
								(size 1.27 1.27)
							)
						)
					)
					(number "22"
						(effects
							(font
								(size 1.27 1.27)
							)
						)
					)
				)
				(pin passive line
					(at 0 -55.88 0)
					(length 3.81)
					(name "~"
						(effects
							(font
								(size 1.27 1.27)
							)
						)
					)
					(number "23"
						(effects
							(font
								(size 1.27 1.27)
							)
						)
					)
				)
				(pin passive line
					(at 0 -58.42 0)
					(length 3.81)
					(name "~"
						(effects
							(font
								(size 1.27 1.27)
							)
						)
					)
					(number "24"
						(effects
							(font
								(size 1.27 1.27)
							)
						)
					)
				)
				(pin passive line
					(at 0 -60.96 0)
					(length 3.81)
					(name "~"
						(effects
							(font
								(size 1.27 1.27)
							)
						)
					)
					(number "25"
						(effects
							(font
								(size 1.27 1.27)
							)
						)
					)
				)
				(pin passive line
					(at 0 -63.5 0)
					(length 3.81)
					(name "~"
						(effects
							(font
								(size 1.27 1.27)
							)
						)
					)
					(number "26"
						(effects
							(font
								(size 1.27 1.27)
							)
						)
					)
				)
				(pin passive line
					(at 0 -66.04 0)
					(length 3.81)
					(name "~"
						(effects
							(font
								(size 1.27 1.27)
							)
						)
					)
					(number "27"
						(effects
							(font
								(size 1.27 1.27)
							)
						)
					)
				)
				(pin passive line
					(at 0 -68.58 0)
					(length 3.81)
					(name "~"
						(effects
							(font
								(size 1.27 1.27)
							)
						)
					)
					(number "28"
						(effects
							(font
								(size 1.27 1.27)
							)
						)
					)
				)
				(pin passive line
					(at 0 -71.12 0)
					(length 3.81)
					(name "~"
						(effects
							(font
								(size 1.27 1.27)
							)
						)
					)
					(number "29"
						(effects
							(font
								(size 1.27 1.27)
							)
						)
					)
				)
				(pin passive line
					(at 0 -73.66 0)
					(length 3.81)
					(name "~"
						(effects
							(font
								(size 1.27 1.27)
							)
						)
					)
					(number "30"
						(effects
							(font
								(size 1.27 1.27)
							)
						)
					)
				)
				(pin passive line
					(at 0 -76.2 0)
					(length 3.81)
					(name "~"
						(effects
							(font
								(size 1.27 1.27)
							)
						)
					)
					(number "31"
						(effects
							(font
								(size 1.27 1.27)
							)
						)
					)
				)
				(pin passive line
					(at 0 -78.74 0)
					(length 3.81)
					(name "~"
						(effects
							(font
								(size 1.27 1.27)
							)
						)
					)
					(number "32"
						(effects
							(font
								(size 1.27 1.27)
							)
						)
					)
				)
				(pin passive line
					(at 0 -81.28 0)
					(length 3.81)
					(name "~"
						(effects
							(font
								(size 1.27 1.27)
							)
						)
					)
					(number "33"
						(effects
							(font
								(size 1.27 1.27)
							)
						)
					)
				)
				(pin passive line
					(at 0 -83.82 0)
					(length 3.81)
					(name "~"
						(effects
							(font
								(size 1.27 1.27)
							)
						)
					)
					(number "34"
						(effects
							(font
								(size 1.27 1.27)
							)
						)
					)
				)
				(pin passive line
					(at 0 -86.36 0)
					(length 3.81)
					(name "~"
						(effects
							(font
								(size 1.27 1.27)
							)
						)
					)
					(number "35"
						(effects
							(font
								(size 1.27 1.27)
							)
						)
					)
				)
				(pin passive line
					(at 0 -88.9 0)
					(length 3.81)
					(name "~"
						(effects
							(font
								(size 1.27 1.27)
							)
						)
					)
					(number "36"
						(effects
							(font
								(size 1.27 1.27)
							)
						)
					)
				)
				(pin passive line
					(at 0 -91.44 0)
					(length 3.81)
					(name "~"
						(effects
							(font
								(size 1.27 1.27)
							)
						)
					)
					(number "37"
						(effects
							(font
								(size 1.27 1.27)
							)
						)
					)
				)
				(pin passive line
					(at 0 -93.98 0)
					(length 3.81)
					(name "~"
						(effects
							(font
								(size 1.27 1.27)
							)
						)
					)
					(number "38"
						(effects
							(font
								(size 1.27 1.27)
							)
						)
					)
				)
				(pin passive line
					(at 0 -96.52 0)
					(length 3.81)
					(name "~"
						(effects
							(font
								(size 1.27 1.27)
							)
						)
					)
					(number "39"
						(effects
							(font
								(size 1.27 1.27)
							)
						)
					)
				)
				(pin passive line
					(at 0 -99.06 0)
					(length 3.81)
					(name "~"
						(effects
							(font
								(size 1.27 1.27)
							)
						)
					)
					(number "40"
						(effects
							(font
								(size 1.27 1.27)
							)
						)
					)
				)
				(pin passive line
					(at 0 -101.6 0)
					(length 3.81)
					(name "~"
						(effects
							(font
								(size 1.27 1.27)
							)
						)
					)
					(number "41"
						(effects
							(font
								(size 1.27 1.27)
							)
						)
					)
				)
				(pin passive line
					(at 0 -104.14 0)
					(length 3.81)
					(name "~"
						(effects
							(font
								(size 1.27 1.27)
							)
						)
					)
					(number "42"
						(effects
							(font
								(size 1.27 1.27)
							)
						)
					)
				)
				(pin passive line
					(at 0 -106.68 0)
					(length 3.81)
					(name "~"
						(effects
							(font
								(size 1.27 1.27)
							)
						)
					)
					(number "43"
						(effects
							(font
								(size 1.27 1.27)
							)
						)
					)
				)
				(pin passive line
					(at 0 -109.22 0)
					(length 3.81)
					(name "~"
						(effects
							(font
								(size 1.27 1.27)
							)
						)
					)
					(number "44"
						(effects
							(font
								(size 1.27 1.27)
							)
						)
					)
				)
				(pin passive line
					(at 0 -111.76 0)
					(length 3.81)
					(name "~"
						(effects
							(font
								(size 1.27 1.27)
							)
						)
					)
					(number "45"
						(effects
							(font
								(size 1.27 1.27)
							)
						)
					)
				)
				(pin passive line
					(at 0 -114.3 0)
					(length 3.81)
					(name "~"
						(effects
							(font
								(size 1.27 1.27)
							)
						)
					)
					(number "46"
						(effects
							(font
								(size 1.27 1.27)
							)
						)
					)
				)
				(pin passive line
					(at 0 -116.84 0)
					(length 3.81)
					(name "~"
						(effects
							(font
								(size 1.27 1.27)
							)
						)
					)
					(number "47"
						(effects
							(font
								(size 1.27 1.27)
							)
						)
					)
				)
				(pin passive line
					(at 0 -119.38 0)
					(length 3.81)
					(name "~"
						(effects
							(font
								(size 1.27 1.27)
							)
						)
					)
					(number "48"
						(effects
							(font
								(size 1.27 1.27)
							)
						)
					)
				)
				(pin passive line
					(at 0 -121.92 0)
					(length 3.81)
					(name "~"
						(effects
							(font
								(size 1.27 1.27)
							)
						)
					)
					(number "49"
						(effects
							(font
								(size 1.27 1.27)
							)
						)
					)
				)
				(pin passive line
					(at 0 -124.46 0)
					(length 3.81)
					(name "~"
						(effects
							(font
								(size 1.27 1.27)
							)
						)
					)
					(number "50"
						(effects
							(font
								(size 1.27 1.27)
							)
						)
					)
				)
				(pin passive line
					(at 0 -127 0)
					(length 3.81)
					(name "MP"
						(effects
							(font
								(size 1.27 1.27)
							)
						)
					)
					(number "MP1"
						(effects
							(font
								(size 1.27 1.27)
							)
						)
					)
				)
				(pin passive line
					(at 0 -129.54 0)
					(length 3.81)
					(name "MP"
						(effects
							(font
								(size 1.27 1.27)
							)
						)
					)
					(number "MP2"
						(effects
							(font
								(size 1.27 1.27)
							)
						)
					)
				)
			)
		)
	(symbol "antmicroFPGAChips:CrossLink_LIFCL-40-9BG256C"
			(exclude_from_sim no)
			(in_bom yes)
			(on_board yes)
			(property "Reference" "U"
				(at 53.34 0 0)
				(effects
					(font
						(size 1.27 1.27)
						(thickness 0.15)
					)
					(justify left bottom)
				)
			)
			(property "Value" "CrossLink_LIFCL-40-9BG256C"
				(at 53.34 -5.08 0)
				(effects
					(font
						(size 1.27 1.27)
						(thickness 0.15)
					)
					(justify left bottom)
					(hide yes)
				)
			)
			(property "Footprint" "antmicro-footprints:BGA-256_14x14mm_Layout16x16_P0.8mm"
				(at 53.34 -7.62 0)
				(effects
					(font
						(size 1.27 1.27)
						(thickness 0.15)
					)
					(justify left bottom)
					(hide yes)
				)
			)
			(property "Datasheet" "https://www.latticesemi.com/-/media/LatticeSemi/Documents/DataSheets/CrossLink/FPGA-DS-02007-2-1-CrossLink-Family-Data-Sheet.ashx?document_id=51662"
				(at 53.34 -10.16 0)
				(effects
					(font
						(size 1.27 1.27)
						(thickness 0.15)
					)
					(justify left bottom)
					(hide yes)
				)
			)
			(property "Description" "CrossLink-NX™ Field Programmable Gate Array 256-LFBGA"
				(at 53.34 -20.32 0)
				(effects
					(font
						(size 1.27 1.27)
					)
					(justify left bottom)
					(hide yes)
				)
			)
			(property "MPN" "LIFCL-40-9BG256C"
				(at 53.34 -2.54 0)
				(effects
					(font
						(size 1.27 1.27)
						(thickness 0.15)
					)
					(justify left bottom)
				)
			)
			(property "Manufacturer" "Lattice Semiconductor"
				(at 53.34 -12.7 0)
				(effects
					(font
						(size 1.27 1.27)
						(thickness 0.15)
					)
					(justify left bottom)
					(hide yes)
				)
			)
			(property "Author" "Antmicro"
				(at 53.34 -15.24 0)
				(effects
					(font
						(size 1.27 1.27)
						(thickness 0.15)
					)
					(justify left bottom)
					(hide yes)
				)
			)
			(property "License" "Apache-2.0"
				(at 53.34 -17.78 0)
				(effects
					(font
						(size 1.27 1.27)
						(thickness 0.15)
					)
					(justify left bottom)
					(hide yes)
				)
			)
			(property "ki_locked" ""
				(at 0 0 0)
				(effects
					(font
						(size 1.27 1.27)
					)
				)
			)
			(property "ki_keywords" "SMT, FPGA, IC"
				(at 0 0 0)
				(effects
					(font
						(size 1.27 1.27)
					)
					(hide yes)
				)
			)
			(symbol "CrossLink_LIFCL-40-9BG256C_1_1"
				(rectangle
					(start 3.81 -33.02)
					(end 41.91 2.54)
					(stroke
						(width 0.254)
						(type default)
					)
					(fill
						(type background)
					)
				)
				(text "BANK0"
					(at 40.64 -31.75 0)
					(effects
						(font
							(size 1.27 1.27)
							(thickness 0.15)
						)
						(justify right bottom)
					)
				)
				(pin power_in line
					(at 0 0 0)
					(length 3.81)
					(name "VCCIO0"
						(effects
							(font
								(size 1.27 1.27)
							)
						)
					)
					(number "D13"
						(effects
							(font
								(size 1.27 1.27)
							)
						)
					)
				)
				(pin bidirectional line
					(at 0 -2.54 0)
					(length 3.81)
					(name "PT74A/INITN\n"
						(effects
							(font
								(size 1.27 1.27)
							)
						)
					)
					(number "D11"
						(effects
							(font
								(size 1.27 1.27)
							)
						)
					)
				)
				(pin bidirectional line
					(at 0 -5.08 0)
					(length 3.81)
					(name "PT74B/PROGRAMN"
						(effects
							(font
								(size 1.27 1.27)
							)
						)
					)
					(number "C12"
						(effects
							(font
								(size 1.27 1.27)
							)
						)
					)
				)
				(pin bidirectional line
					(at 0 -7.62 0)
					(length 3.81)
					(name "PT76A/MCLK/PCLKT0_0"
						(effects
							(font
								(size 1.27 1.27)
							)
						)
					)
					(number "C16"
						(effects
							(font
								(size 1.27 1.27)
							)
						)
					)
				)
				(pin bidirectional line
					(at 0 -10.16 0)
					(length 3.81)
					(name "PT76B/DONE\n"
						(effects
							(font
								(size 1.27 1.27)
							)
						)
					)
					(number "B16"
						(effects
							(font
								(size 1.27 1.27)
							)
						)
					)
				)
				(pin bidirectional line
					(at 0 -12.7 0)
					(length 3.81)
					(name "PT78A/MCSN/PCLKT0_1"
						(effects
							(font
								(size 1.27 1.27)
							)
						)
					)
					(number "C15"
						(effects
							(font
								(size 1.27 1.27)
							)
						)
					)
				)
				(pin bidirectional line
					(at 0 -15.24 0)
					(length 3.81)
					(name "PT78B/MOSI/MD0"
						(effects
							(font
								(size 1.27 1.27)
							)
						)
					)
					(number "C14"
						(effects
							(font
								(size 1.27 1.27)
							)
						)
					)
				)
				(pin bidirectional line
					(at 0 -17.78 0)
					(length 3.81)
					(name "PT80A/MISO/MD1"
						(effects
							(font
								(size 1.27 1.27)
							)
						)
					)
					(number "D16"
						(effects
							(font
								(size 1.27 1.27)
							)
						)
					)
				)
				(pin bidirectional line
					(at 0 -20.32 0)
					(length 3.81)
					(name "PT80B/MD2"
						(effects
							(font
								(size 1.27 1.27)
							)
						)
					)
					(number "D15"
						(effects
							(font
								(size 1.27 1.27)
							)
						)
					)
				)
				(pin bidirectional line
					(at 0 -22.86 0)
					(length 3.81)
					(name "PT82A/MD3"
						(effects
							(font
								(size 1.27 1.27)
							)
						)
					)
					(number "D12"
						(effects
							(font
								(size 1.27 1.27)
							)
						)
					)
				)
				(pin bidirectional line
					(at 0 -25.4 0)
					(length 3.81)
					(name "PT82B/MCSNO/MSDO"
						(effects
							(font
								(size 1.27 1.27)
							)
						)
					)
					(number "C13"
						(effects
							(font
								(size 1.27 1.27)
							)
						)
					)
				)
				(pin bidirectional line
					(at 0 -27.94 0)
					(length 3.81)
					(name "PT84A"
						(effects
							(font
								(size 1.27 1.27)
							)
						)
					)
					(number "E15"
						(effects
							(font
								(size 1.27 1.27)
							)
						)
					)
				)
				(pin bidirectional line
					(at 0 -30.48 0)
					(length 3.81)
					(name "PT84B"
						(effects
							(font
								(size 1.27 1.27)
							)
						)
					)
					(number "E16"
						(effects
							(font
								(size 1.27 1.27)
							)
						)
					)
				)
			)
			(symbol "CrossLink_LIFCL-40-9BG256C_2_1"
				(rectangle
					(start 3.81 -55.88)
					(end 41.91 2.54)
					(stroke
						(width 0.254)
						(type default)
					)
					(fill
						(type background)
					)
				)
				(text "BANK1"
					(at 40.64 -54.61 0)
					(effects
						(font
							(size 1.27 1.27)
							(thickness 0.15)
						)
						(justify right bottom)
					)
				)
				(pin power_in line
					(at 0 0 0)
					(length 3.81)
					(name "VCCIO1"
						(effects
							(font
								(size 1.27 1.27)
							)
						)
					)
					(number "F13"
						(effects
							(font
								(size 1.27 1.27)
							)
						)
					)
				)
				(pin input line
					(at 0 -2.54 0)
					(length 3.81)
					(name "JTAG_EN"
						(effects
							(font
								(size 1.27 1.27)
							)
						)
					)
					(number "D10"
						(effects
							(font
								(size 1.27 1.27)
							)
						)
					)
				)
				(pin bidirectional line
					(at 0 -5.08 0)
					(length 3.81)
					(name "PR3B"
						(effects
							(font
								(size 1.27 1.27)
							)
						)
					)
					(number "F9"
						(effects
							(font
								(size 1.27 1.27)
							)
						)
					)
				)
				(pin bidirectional line
					(at 0 -7.62 0)
					(length 3.81)
					(name "PR4A"
						(effects
							(font
								(size 1.27 1.27)
							)
						)
					)
					(number "E9"
						(effects
							(font
								(size 1.27 1.27)
							)
						)
					)
				)
				(pin bidirectional line
					(at 0 -10.16 0)
					(length 3.81)
					(name "PR4B"
						(effects
							(font
								(size 1.27 1.27)
							)
						)
					)
					(number "E10"
						(effects
							(font
								(size 1.27 1.27)
							)
						)
					)
				)
				(pin bidirectional line
					(at 0 -12.7 0)
					(length 3.81)
					(name "PR6A"
						(effects
							(font
								(size 1.27 1.27)
							)
						)
					)
					(number "E12"
						(effects
							(font
								(size 1.27 1.27)
							)
						)
					)
				)
				(pin bidirectional line
					(at 0 -15.24 0)
					(length 3.81)
					(name "PR6B/TMS/SCSN"
						(effects
							(font
								(size 1.27 1.27)
							)
						)
					)
					(number "E11"
						(effects
							(font
								(size 1.27 1.27)
							)
						)
					)
				)
				(pin bidirectional line
					(at 0 -17.78 0)
					(length 3.81)
					(name "PR8A"
						(effects
							(font
								(size 1.27 1.27)
							)
						)
					)
					(number "F10"
						(effects
							(font
								(size 1.27 1.27)
							)
						)
					)
				)
				(pin bidirectional line
					(at 0 -20.32 0)
					(length 3.81)
					(name "PR8B/TDI/SSI"
						(effects
							(font
								(size 1.27 1.27)
							)
						)
					)
					(number "F11"
						(effects
							(font
								(size 1.27 1.27)
							)
						)
					)
				)
				(pin bidirectional line
					(at 0 -22.86 0)
					(length 3.81)
					(name "PR10A"
						(effects
							(font
								(size 1.27 1.27)
							)
						)
					)
					(number "E13"
						(effects
							(font
								(size 1.27 1.27)
							)
						)
					)
				)
				(pin bidirectional line
					(at 0 -25.4 0)
					(length 3.81)
					(name "PR10B/TDO/SSO"
						(effects
							(font
								(size 1.27 1.27)
							)
						)
					)
					(number "E14"
						(effects
							(font
								(size 1.27 1.27)
							)
						)
					)
				)
				(pin bidirectional line
					(at 0 -27.94 0)
					(length 3.81)
					(name "PR11A/SDA/USER_SDA"
						(effects
							(font
								(size 1.27 1.27)
							)
						)
					)
					(number "G9"
						(effects
							(font
								(size 1.27 1.27)
							)
						)
					)
				)
				(pin bidirectional line
					(at 0 -30.48 0)
					(length 3.81)
					(name "PR11B/SCL/USER_SCL"
						(effects
							(font
								(size 1.27 1.27)
							)
						)
					)
					(number "G10"
						(effects
							(font
								(size 1.27 1.27)
							)
						)
					)
				)
				(pin bidirectional line
					(at 0 -33.02 0)
					(length 3.81)
					(name "PR13A/TCK/SCLK"
						(effects
							(font
								(size 1.27 1.27)
							)
						)
					)
					(number "F14"
						(effects
							(font
								(size 1.27 1.27)
							)
						)
					)
				)
				(pin bidirectional line
					(at 0 -35.56 0)
					(length 3.81)
					(name "PR13B"
						(effects
							(font
								(size 1.27 1.27)
							)
						)
					)
					(number "F15"
						(effects
							(font
								(size 1.27 1.27)
							)
						)
					)
				)
				(pin bidirectional line
					(at 0 -38.1 0)
					(length 3.81)
					(name "PR15A"
						(effects
							(font
								(size 1.27 1.27)
							)
						)
					)
					(number "G11"
						(effects
							(font
								(size 1.27 1.27)
							)
						)
					)
				)
				(pin bidirectional line
					(at 0 -40.64 0)
					(length 3.81)
					(name "PR15B"
						(effects
							(font
								(size 1.27 1.27)
							)
						)
					)
					(number "G12"
						(effects
							(font
								(size 1.27 1.27)
							)
						)
					)
				)
				(pin bidirectional line
					(at 0 -43.18 0)
					(length 3.81)
					(name "PR17A/PCLKT1_2"
						(effects
							(font
								(size 1.27 1.27)
							)
						)
					)
					(number "G13"
						(effects
							(font
								(size 1.27 1.27)
							)
						)
					)
				)
				(pin bidirectional line
					(at 0 -45.72 0)
					(length 3.81)
					(name "PR17B"
						(effects
							(font
								(size 1.27 1.27)
							)
						)
					)
					(number "G14"
						(effects
							(font
								(size 1.27 1.27)
							)
						)
					)
				)
				(pin bidirectional line
					(at 0 -48.26 0)
					(length 3.81)
					(name "PR19A/PCLKT1_1"
						(effects
							(font
								(size 1.27 1.27)
							)
						)
					)
					(number "F16"
						(effects
							(font
								(size 1.27 1.27)
							)
						)
					)
				)
				(pin bidirectional line
					(at 0 -50.8 0)
					(length 3.81)
					(name "PR19B"
						(effects
							(font
								(size 1.27 1.27)
							)
						)
					)
					(number "G16"
						(effects
							(font
								(size 1.27 1.27)
							)
						)
					)
				)
				(pin bidirectional line
					(at 0 -53.34 0)
					(length 3.81)
					(name "PR20A/PCLKT1_0\n"
						(effects
							(font
								(size 1.27 1.27)
							)
						)
					)
					(number "G15"
						(effects
							(font
								(size 1.27 1.27)
							)
						)
					)
				)
			)
			(symbol "CrossLink_LIFCL-40-9BG256C_3_1"
				(rectangle
					(start 3.81 -35.56)
					(end 41.91 2.54)
					(stroke
						(width 0.254)
						(type default)
					)
					(fill
						(type background)
					)
				)
				(text "BANK2"
					(at 40.64 -34.29 0)
					(effects
						(font
							(size 1.27 1.27)
							(thickness 0.15)
						)
						(justify right bottom)
					)
				)
				(pin power_in line
					(at 0 0 0)
					(length 3.81)
					(name "VCCIO2"
						(effects
							(font
								(size 1.27 1.27)
							)
						)
					)
					(number "J13"
						(effects
							(font
								(size 1.27 1.27)
							)
						)
					)
				)
				(pin bidirectional line
					(at 0 -2.54 0)
					(length 3.81)
					(name "PR26A"
						(effects
							(font
								(size 1.27 1.27)
							)
						)
					)
					(number "H16"
						(effects
							(font
								(size 1.27 1.27)
							)
						)
					)
				)
				(pin bidirectional line
					(at 0 -5.08 0)
					(length 3.81)
					(name "PR27A"
						(effects
							(font
								(size 1.27 1.27)
							)
						)
					)
					(number "H15"
						(effects
							(font
								(size 1.27 1.27)
							)
						)
					)
				)
				(pin bidirectional line
					(at 0 -7.62 0)
					(length 3.81)
					(name "PR27B"
						(effects
							(font
								(size 1.27 1.27)
							)
						)
					)
					(number "H14"
						(effects
							(font
								(size 1.27 1.27)
							)
						)
					)
				)
				(pin bidirectional line
					(at 0 -10.16 0)
					(length 3.81)
					(name "PR30A/PCLKT2_0"
						(effects
							(font
								(size 1.27 1.27)
							)
						)
					)
					(number "H11"
						(effects
							(font
								(size 1.27 1.27)
							)
						)
					)
				)
				(pin bidirectional line
					(at 0 -12.7 0)
					(length 3.81)
					(name "PR30B"
						(effects
							(font
								(size 1.27 1.27)
							)
						)
					)
					(number "H10"
						(effects
							(font
								(size 1.27 1.27)
							)
						)
					)
				)
				(pin bidirectional line
					(at 0 -15.24 0)
					(length 3.81)
					(name "PR32A/PCLKT2_1"
						(effects
							(font
								(size 1.27 1.27)
							)
						)
					)
					(number "H13"
						(effects
							(font
								(size 1.27 1.27)
							)
						)
					)
				)
				(pin bidirectional line
					(at 0 -17.78 0)
					(length 3.81)
					(name "PR32B"
						(effects
							(font
								(size 1.27 1.27)
							)
						)
					)
					(number "H12"
						(effects
							(font
								(size 1.27 1.27)
							)
						)
					)
				)
				(pin bidirectional line
					(at 0 -20.32 0)
					(length 3.81)
					(name "PR34A/PCLKT2_2"
						(effects
							(font
								(size 1.27 1.27)
							)
						)
					)
					(number "J16"
						(effects
							(font
								(size 1.27 1.27)
							)
						)
					)
				)
				(pin bidirectional line
					(at 0 -22.86 0)
					(length 3.81)
					(name "PR34B"
						(effects
							(font
								(size 1.27 1.27)
							)
						)
					)
					(number "J15"
						(effects
							(font
								(size 1.27 1.27)
							)
						)
					)
				)
				(pin bidirectional line
					(at 0 -25.4 0)
					(length 3.81)
					(name "PR36A"
						(effects
							(font
								(size 1.27 1.27)
							)
						)
					)
					(number "J11"
						(effects
							(font
								(size 1.27 1.27)
							)
						)
					)
				)
				(pin bidirectional line
					(at 0 -27.94 0)
					(length 3.81)
					(name "PR36B"
						(effects
							(font
								(size 1.27 1.27)
							)
						)
					)
					(number "J12"
						(effects
							(font
								(size 1.27 1.27)
							)
						)
					)
				)
				(pin bidirectional line
					(at 0 -30.48 0)
					(length 3.81)
					(name "PR38A"
						(effects
							(font
								(size 1.27 1.27)
							)
						)
					)
					(number "K11"
						(effects
							(font
								(size 1.27 1.27)
							)
						)
					)
				)
				(pin bidirectional line
					(at 0 -33.02 0)
					(length 3.81)
					(name "PR38B"
						(effects
							(font
								(size 1.27 1.27)
							)
						)
					)
					(number "K12"
						(effects
							(font
								(size 1.27 1.27)
							)
						)
					)
				)
			)
			(symbol "CrossLink_LIFCL-40-9BG256C_4_1"
				(rectangle
					(start 3.81 -83.82)
					(end 41.91 2.54)
					(stroke
						(width 0.254)
						(type default)
					)
					(fill
						(type background)
					)
				)
				(text "BANK3"
					(at 40.64 -77.47 0)
					(effects
						(font
							(size 1.27 1.27)
							(thickness 0.15)
						)
						(justify right bottom)
					)
				)
				(pin bidirectional line
					(at 0 0 0)
					(length 3.81)
					(name "VCCIO3"
						(effects
							(font
								(size 1.27 1.27)
							)
						)
					)
					(number "P12"
						(effects
							(font
								(size 1.27 1.27)
							)
						)
					)
				)
				(pin bidirectional line
					(at 0 -2.54 0)
					(length 3.81)
					(name "PB54A/PCLKT3_0/VREF3_1/ADC_CP5"
						(effects
							(font
								(size 1.27 1.27)
							)
						)
					)
					(number "R11"
						(effects
							(font
								(size 1.27 1.27)
							)
						)
					)
				)
				(pin bidirectional line
					(at 0 -5.08 0)
					(length 3.81)
					(name "PB54B/PCLKC3_0/ADC_CN5\n"
						(effects
							(font
								(size 1.27 1.27)
							)
						)
					)
					(number "P11"
						(effects
							(font
								(size 1.27 1.27)
							)
						)
					)
				)
				(pin bidirectional line
					(at 0 -7.62 0)
					(length 3.81)
					(name "PB56A/ADC_CP7\n"
						(effects
							(font
								(size 1.27 1.27)
							)
						)
					)
					(number "P10"
						(effects
							(font
								(size 1.27 1.27)
							)
						)
					)
				)
				(pin bidirectional line
					(at 0 -10.16 0)
					(length 3.81)
					(name "PB56B/ADC_CN7\n"
						(effects
							(font
								(size 1.27 1.27)
							)
						)
					)
					(number "R10"
						(effects
							(font
								(size 1.27 1.27)
							)
						)
					)
				)
				(pin bidirectional line
					(at 0 -12.7 0)
					(length 3.81)
					(name "PB58A/PCLKT3_1/ADC_CP6\n"
						(effects
							(font
								(size 1.27 1.27)
							)
						)
					)
					(number "T12"
						(effects
							(font
								(size 1.27 1.27)
							)
						)
					)
				)
				(pin bidirectional line
					(at 0 -15.24 0)
					(length 3.81)
					(name "PB58B/PCLKC3_1/ADC_CN6\n"
						(effects
							(font
								(size 1.27 1.27)
							)
						)
					)
					(number "T11"
						(effects
							(font
								(size 1.27 1.27)
							)
						)
					)
				)
				(pin bidirectional line
					(at 0 -17.78 0)
					(length 3.81)
					(name "PB60A/ADC_CP9"
						(effects
							(font
								(size 1.27 1.27)
							)
						)
					)
					(number "R12"
						(effects
							(font
								(size 1.27 1.27)
							)
						)
					)
				)
				(pin bidirectional line
					(at 0 -20.32 0)
					(length 3.81)
					(name "PB60B/ADC_CN9"
						(effects
							(font
								(size 1.27 1.27)
							)
						)
					)
					(number "T13"
						(effects
							(font
								(size 1.27 1.27)
							)
						)
					)
				)
				(pin bidirectional line
					(at 0 -22.86 0)
					(length 3.81)
					(name "PB62A/ADC_CP10"
						(effects
							(font
								(size 1.27 1.27)
							)
						)
					)
					(number "R13"
						(effects
							(font
								(size 1.27 1.27)
							)
						)
					)
				)
				(pin bidirectional line
					(at 0 -25.4 0)
					(length 3.81)
					(name "PB62B/ADC_CN10"
						(effects
							(font
								(size 1.27 1.27)
							)
						)
					)
					(number "R14"
						(effects
							(font
								(size 1.27 1.27)
							)
						)
					)
				)
				(pin bidirectional line
					(at 0 -27.94 0)
					(length 3.81)
					(name "PB64A/ADC_CP4"
						(effects
							(font
								(size 1.27 1.27)
							)
						)
					)
					(number "N12"
						(effects
							(font
								(size 1.27 1.27)
							)
						)
					)
				)
				(pin bidirectional line
					(at 0 -30.48 0)
					(length 3.81)
					(name "PB64B/ADC_CN4"
						(effects
							(font
								(size 1.27 1.27)
							)
						)
					)
					(number "N11"
						(effects
							(font
								(size 1.27 1.27)
							)
						)
					)
				)
				(pin bidirectional line
					(at 0 -33.02 0)
					(length 3.81)
					(name "PB66A/COMP1IP"
						(effects
							(font
								(size 1.27 1.27)
							)
						)
					)
					(number "T14"
						(effects
							(font
								(size 1.27 1.27)
							)
						)
					)
				)
				(pin bidirectional line
					(at 0 -35.56 0)
					(length 3.81)
					(name "PB66B/COMP1IN"
						(effects
							(font
								(size 1.27 1.27)
							)
						)
					)
					(number "T15"
						(effects
							(font
								(size 1.27 1.27)
							)
						)
					)
				)
				(pin bidirectional line
					(at 0 -38.1 0)
					(length 3.81)
					(name "PB68A/ADC_CP8"
						(effects
							(font
								(size 1.27 1.27)
							)
						)
					)
					(number "R16"
						(effects
							(font
								(size 1.27 1.27)
							)
						)
					)
				)
				(pin bidirectional line
					(at 0 -40.64 0)
					(length 3.81)
					(name "PB68B/ADC_CN8"
						(effects
							(font
								(size 1.27 1.27)
							)
						)
					)
					(number "R15"
						(effects
							(font
								(size 1.27 1.27)
							)
						)
					)
				)
				(pin bidirectional line
					(at 0 -43.18 0)
					(length 3.81)
					(name "PB70A/COMP2IP"
						(effects
							(font
								(size 1.27 1.27)
							)
						)
					)
					(number "P14"
						(effects
							(font
								(size 1.27 1.27)
							)
						)
					)
				)
				(pin bidirectional line
					(at 0 -45.72 0)
					(length 3.81)
					(name "PB70B/COMP2IN\n"
						(effects
							(font
								(size 1.27 1.27)
							)
						)
					)
					(number "N13"
						(effects
							(font
								(size 1.27 1.27)
							)
						)
					)
				)
				(pin bidirectional line
					(at 0 -48.26 0)
					(length 3.81)
					(name "PB72A/PCLKT3_2/ADC_CP13"
						(effects
							(font
								(size 1.27 1.27)
							)
						)
					)
					(number "P15"
						(effects
							(font
								(size 1.27 1.27)
							)
						)
					)
				)
				(pin bidirectional line
					(at 0 -50.8 0)
					(length 3.81)
					(name "PB72B/PCLKC3_2/ADC_CN13"
						(effects
							(font
								(size 1.27 1.27)
							)
						)
					)
					(number "P16"
						(effects
							(font
								(size 1.27 1.27)
							)
						)
					)
				)
				(pin bidirectional line
					(at 0 -53.34 0)
					(length 3.81)
					(name "PB74A/PCLKT3_3/ADC_CP14"
						(effects
							(font
								(size 1.27 1.27)
							)
						)
					)
					(number "M14"
						(effects
							(font
								(size 1.27 1.27)
							)
						)
					)
				)
				(pin bidirectional line
					(at 0 -55.88 0)
					(length 3.81)
					(name "PB74B/PCLKC3_3/ADC_CN14"
						(effects
							(font
								(size 1.27 1.27)
							)
						)
					)
					(number "N14"
						(effects
							(font
								(size 1.27 1.27)
							)
						)
					)
				)
				(pin bidirectional line
					(at 0 -58.42 0)
					(length 3.81)
					(name "PB76A/COMP3IP"
						(effects
							(font
								(size 1.27 1.27)
							)
						)
					)
					(number "N16"
						(effects
							(font
								(size 1.27 1.27)
							)
						)
					)
				)
				(pin bidirectional line
					(at 0 -60.96 0)
					(length 3.81)
					(name "PB76B/COMP3IN"
						(effects
							(font
								(size 1.27 1.27)
							)
						)
					)
					(number "N15"
						(effects
							(font
								(size 1.27 1.27)
							)
						)
					)
				)
				(pin bidirectional line
					(at 0 -63.5 0)
					(length 3.81)
					(name "PB78A/ADC_CP11"
						(effects
							(font
								(size 1.27 1.27)
							)
						)
					)
					(number "M12"
						(effects
							(font
								(size 1.27 1.27)
							)
						)
					)
				)
				(pin bidirectional line
					(at 0 -66.04 0)
					(length 3.81)
					(name "PB78B/ADC_CN11"
						(effects
							(font
								(size 1.27 1.27)
							)
						)
					)
					(number "M11"
						(effects
							(font
								(size 1.27 1.27)
							)
						)
					)
				)
				(pin bidirectional line
					(at 0 -68.58 0)
					(length 3.81)
					(name "PB80A/ADC_CP12"
						(effects
							(font
								(size 1.27 1.27)
							)
						)
					)
					(number "L11"
						(effects
							(font
								(size 1.27 1.27)
							)
						)
					)
				)
				(pin bidirectional line
					(at 0 -71.12 0)
					(length 3.81)
					(name "PB80B/ADC_CN12"
						(effects
							(font
								(size 1.27 1.27)
							)
						)
					)
					(number "L10"
						(effects
							(font
								(size 1.27 1.27)
							)
						)
					)
				)
				(pin bidirectional line
					(at 0 -73.66 0)
					(length 3.81)
					(name "PB82A/ADC_CP15"
						(effects
							(font
								(size 1.27 1.27)
							)
						)
					)
					(number "M13"
						(effects
							(font
								(size 1.27 1.27)
							)
						)
					)
				)
				(pin bidirectional line
					(at 0 -76.2 0)
					(length 3.81)
					(name "PB82B/ADC_CN15"
						(effects
							(font
								(size 1.27 1.27)
							)
						)
					)
					(number "L12"
						(effects
							(font
								(size 1.27 1.27)
							)
						)
					)
				)
				(pin bidirectional line
					(at 0 -78.74 0)
					(length 3.81)
					(name "PB84A/LRC_GPLL0T_IN"
						(effects
							(font
								(size 1.27 1.27)
							)
						)
					)
					(number "M16"
						(effects
							(font
								(size 1.27 1.27)
							)
						)
					)
				)
				(pin bidirectional line
					(at 0 -81.28 0)
					(length 3.81)
					(name "PB84B/LRC_GPLL0C_IN/VREF3_2"
						(effects
							(font
								(size 1.27 1.27)
							)
						)
					)
					(number "M15"
						(effects
							(font
								(size 1.27 1.27)
							)
						)
					)
				)
			)
			(symbol "CrossLink_LIFCL-40-9BG256C_5_1"
				(rectangle
					(start 3.81 2.54)
					(end 41.91 -83.82)
					(stroke
						(width 0.254)
						(type default)
					)
					(fill
						(type background)
					)
				)
				(text "BANK4"
					(at 40.64 -82.55 0)
					(effects
						(font
							(size 1.27 1.27)
							(thickness 0.15)
						)
						(justify right bottom)
					)
				)
				(pin power_in line
					(at 0 0 0)
					(length 3.81)
					(name "VCCIO4"
						(effects
							(font
								(size 1.27 1.27)
							)
						)
					)
					(number "N6"
						(effects
							(font
								(size 1.27 1.27)
							)
						)
					)
				)
				(pin bidirectional line
					(at 0 -2.54 0)
					(length 3.81)
					(name "PB16A/VREF4_1"
						(effects
							(font
								(size 1.27 1.27)
							)
						)
					)
					(number "R1"
						(effects
							(font
								(size 1.27 1.27)
							)
						)
					)
				)
				(pin bidirectional line
					(at 0 -5.08 0)
					(length 3.81)
					(name "PB16B"
						(effects
							(font
								(size 1.27 1.27)
							)
						)
					)
					(number "R2"
						(effects
							(font
								(size 1.27 1.27)
							)
						)
					)
				)
				(pin bidirectional line
					(at 0 -7.62 0)
					(length 3.81)
					(name "PB18A/PCLKT4_3\n"
						(effects
							(font
								(size 1.27 1.27)
							)
						)
					)
					(number "R3"
						(effects
							(font
								(size 1.27 1.27)
							)
						)
					)
				)
				(pin bidirectional line
					(at 0 -10.16 0)
					(length 3.81)
					(name "PB18B/PCLKC4_3\n"
						(effects
							(font
								(size 1.27 1.27)
							)
						)
					)
					(number "T2"
						(effects
							(font
								(size 1.27 1.27)
							)
						)
					)
				)
				(pin bidirectional line
					(at 0 -12.7 0)
					(length 3.81)
					(name "PB20A"
						(effects
							(font
								(size 1.27 1.27)
							)
						)
					)
					(number "T3"
						(effects
							(font
								(size 1.27 1.27)
							)
						)
					)
				)
				(pin bidirectional line
					(at 0 -15.24 0)
					(length 3.81)
					(name "PB20B"
						(effects
							(font
								(size 1.27 1.27)
							)
						)
					)
					(number "T4"
						(effects
							(font
								(size 1.27 1.27)
							)
						)
					)
				)
				(pin bidirectional line
					(at 0 -17.78 0)
					(length 3.81)
					(name "PB22A"
						(effects
							(font
								(size 1.27 1.27)
							)
						)
					)
					(number "R5"
						(effects
							(font
								(size 1.27 1.27)
							)
						)
					)
				)
				(pin bidirectional line
					(at 0 -20.32 0)
					(length 3.81)
					(name "PB22B"
						(effects
							(font
								(size 1.27 1.27)
							)
						)
					)
					(number "P5"
						(effects
							(font
								(size 1.27 1.27)
							)
						)
					)
				)
				(pin bidirectional line
					(at 0 -22.86 0)
					(length 3.81)
					(name "PB24A/PCLKT4_2"
						(effects
							(font
								(size 1.27 1.27)
							)
						)
					)
					(number "R4"
						(effects
							(font
								(size 1.27 1.27)
							)
						)
					)
				)
				(pin bidirectional line
					(at 0 -25.4 0)
					(length 3.81)
					(name "PB24B/PCLKC4_2\n"
						(effects
							(font
								(size 1.27 1.27)
							)
						)
					)
					(number "P4"
						(effects
							(font
								(size 1.27 1.27)
							)
						)
					)
				)
				(pin bidirectional line
					(at 0 -27.94 0)
					(length 3.81)
					(name "PB26A"
						(effects
							(font
								(size 1.27 1.27)
							)
						)
					)
					(number "T5"
						(effects
							(font
								(size 1.27 1.27)
							)
						)
					)
				)
				(pin bidirectional line
					(at 0 -30.48 0)
					(length 3.81)
					(name "PB26B"
						(effects
							(font
								(size 1.27 1.27)
							)
						)
					)
					(number "R6"
						(effects
							(font
								(size 1.27 1.27)
							)
						)
					)
				)
				(pin bidirectional line
					(at 0 -33.02 0)
					(length 3.81)
					(name "PB28A"
						(effects
							(font
								(size 1.27 1.27)
							)
						)
					)
					(number "T6"
						(effects
							(font
								(size 1.27 1.27)
							)
						)
					)
				)
				(pin bidirectional line
					(at 0 -35.56 0)
					(length 3.81)
					(name "PB28B"
						(effects
							(font
								(size 1.27 1.27)
							)
						)
					)
					(number "R7"
						(effects
							(font
								(size 1.27 1.27)
							)
						)
					)
				)
				(pin bidirectional line
					(at 0 -38.1 0)
					(length 3.81)
					(name "PB30A"
						(effects
							(font
								(size 1.27 1.27)
							)
						)
					)
					(number "T7"
						(effects
							(font
								(size 1.27 1.27)
							)
						)
					)
				)
				(pin bidirectional line
					(at 0 -40.64 0)
					(length 3.81)
					(name "PB30B"
						(effects
							(font
								(size 1.27 1.27)
							)
						)
					)
					(number "T8"
						(effects
							(font
								(size 1.27 1.27)
							)
						)
					)
				)
				(pin bidirectional line
					(at 0 -43.18 0)
					(length 3.81)
					(name "PB32A"
						(effects
							(font
								(size 1.27 1.27)
							)
						)
					)
					(number "P6"
						(effects
							(font
								(size 1.27 1.27)
							)
						)
					)
				)
				(pin bidirectional line
					(at 0 -45.72 0)
					(length 3.81)
					(name "PB32B"
						(effects
							(font
								(size 1.27 1.27)
							)
						)
					)
					(number "P7"
						(effects
							(font
								(size 1.27 1.27)
							)
						)
					)
				)
				(pin bidirectional line
					(at 0 -48.26 0)
					(length 3.81)
					(name "PB34A"
						(effects
							(font
								(size 1.27 1.27)
							)
						)
					)
					(number "L8"
						(effects
							(font
								(size 1.27 1.27)
							)
						)
					)
				)
				(pin bidirectional line
					(at 0 -50.8 0)
					(length 3.81)
					(name "PB34B"
						(effects
							(font
								(size 1.27 1.27)
							)
						)
					)
					(number "L9"
						(effects
							(font
								(size 1.27 1.27)
							)
						)
					)
				)
				(pin bidirectional line
					(at 0 -53.34 0)
					(length 3.81)
					(name "PB36A"
						(effects
							(font
								(size 1.27 1.27)
							)
						)
					)
					(number "N8"
						(effects
							(font
								(size 1.27 1.27)
							)
						)
					)
				)
				(pin bidirectional line
					(at 0 -55.88 0)
					(length 3.81)
					(name "PB36B"
						(effects
							(font
								(size 1.27 1.27)
							)
						)
					)
					(number "N9"
						(effects
							(font
								(size 1.27 1.27)
							)
						)
					)
				)
				(pin bidirectional line
					(at 0 -58.42 0)
					(length 3.81)
					(name "PB38A"
						(effects
							(font
								(size 1.27 1.27)
							)
						)
					)
					(number "M9"
						(effects
							(font
								(size 1.27 1.27)
							)
						)
					)
				)
				(pin bidirectional line
					(at 0 -60.96 0)
					(length 3.81)
					(name "PB38B"
						(effects
							(font
								(size 1.27 1.27)
							)
						)
					)
					(number "M8"
						(effects
							(font
								(size 1.27 1.27)
							)
						)
					)
				)
				(pin bidirectional line
					(at 0 -63.5 0)
					(length 3.81)
					(name "PB40A/PCLKT4_1"
						(effects
							(font
								(size 1.27 1.27)
							)
						)
					)
					(number "T9"
						(effects
							(font
								(size 1.27 1.27)
							)
						)
					)
				)
				(pin bidirectional line
					(at 0 -66.04 0)
					(length 3.81)
					(name "PB40B/PCLKC4_1"
						(effects
							(font
								(size 1.27 1.27)
							)
						)
					)
					(number "T10"
						(effects
							(font
								(size 1.27 1.27)
							)
						)
					)
				)
				(pin bidirectional line
					(at 0 -68.58 0)
					(length 3.81)
					(name "PB42A"
						(effects
							(font
								(size 1.27 1.27)
							)
						)
					)
					(number "R8"
						(effects
							(font
								(size 1.27 1.27)
							)
						)
					)
				)
				(pin bidirectional line
					(at 0 -71.12 0)
					(length 3.81)
					(name "PB42B"
						(effects
							(font
								(size 1.27 1.27)
							)
						)
					)
					(number "P8"
						(effects
							(font
								(size 1.27 1.27)
							)
						)
					)
				)
				(pin bidirectional line
					(at 0 -73.66 0)
					(length 3.81)
					(name "PB44A/PCLKT4_0"
						(effects
							(font
								(size 1.27 1.27)
							)
						)
					)
					(number "R9"
						(effects
							(font
								(size 1.27 1.27)
							)
						)
					)
				)
				(pin bidirectional line
					(at 0 -76.2 0)
					(length 3.81)
					(name "PB44B/PCLKC4_0"
						(effects
							(font
								(size 1.27 1.27)
							)
						)
					)
					(number "P9"
						(effects
							(font
								(size 1.27 1.27)
							)
						)
					)
				)
				(pin bidirectional line
					(at 0 -78.74 0)
					(length 3.81)
					(name "PB46A"
						(effects
							(font
								(size 1.27 1.27)
							)
						)
					)
					(number "M10"
						(effects
							(font
								(size 1.27 1.27)
							)
						)
					)
				)
				(pin bidirectional line
					(at 0 -81.28 0)
					(length 3.81)
					(name "PB46B/VREF4_2"
						(effects
							(font
								(size 1.27 1.27)
							)
						)
					)
					(number "N10"
						(effects
							(font
								(size 1.27 1.27)
							)
						)
					)
				)
			)
			(symbol "CrossLink_LIFCL-40-9BG256C_6_1"
				(rectangle
					(start 3.81 -27.94)
					(end 52.07 2.54)
					(stroke
						(width 0.254)
						(type default)
					)
					(fill
						(type background)
					)
				)
				(text "BANK5"
					(at 50.8 -26.67 0)
					(effects
						(font
							(size 1.27 1.27)
							(thickness 0.15)
						)
						(justify right bottom)
					)
				)
				(pin power_in line
					(at 0 0 0)
					(length 3.81)
					(name "VCCIO5"
						(effects
							(font
								(size 1.27 1.27)
							)
						)
					)
					(number "N5"
						(effects
							(font
								(size 1.27 1.27)
							)
						)
					)
				)
				(pin bidirectional line
					(at 0 -2.54 0)
					(length 3.81)
					(name "PB4A/CDR_RXP0/VREF5_1/ADC_CP0/COMP1P\n"
						(effects
							(font
								(size 1.27 1.27)
							)
						)
					)
					(number "P3"
						(effects
							(font
								(size 1.27 1.27)
							)
						)
					)
				)
				(pin bidirectional line
					(at 0 -5.08 0)
					(length 3.81)
					(name "PB4B/CDR_RXN0/ADC_CN0/COMP1N"
						(effects
							(font
								(size 1.27 1.27)
							)
						)
					)
					(number "N3"
						(effects
							(font
								(size 1.27 1.27)
							)
						)
					)
				)
				(pin bidirectional line
					(at 0 -7.62 0)
					(length 3.81)
					(name "PB6A/PCLKT5_0/CDR_RXP1/ADC_CP1/COMP2P"
						(effects
							(font
								(size 1.27 1.27)
							)
						)
					)
					(number "N4"
						(effects
							(font
								(size 1.27 1.27)
							)
						)
					)
				)
				(pin bidirectional line
					(at 0 -10.16 0)
					(length 3.81)
					(name "PB6B/PCLKC5_0/CDR_RXN1/ADC_CN1/COMP2N"
						(effects
							(font
								(size 1.27 1.27)
							)
						)
					)
					(number "M4"
						(effects
							(font
								(size 1.27 1.27)
							)
						)
					)
				)
				(pin bidirectional line
					(at 0 -12.7 0)
					(length 3.81)
					(name "PB8A/PCLKT5_1/LLC_GPLL0T_IN/ADC_CP3"
						(effects
							(font
								(size 1.27 1.27)
							)
						)
					)
					(number "L7"
						(effects
							(font
								(size 1.27 1.27)
							)
						)
					)
				)
				(pin bidirectional line
					(at 0 -15.24 0)
					(length 3.81)
					(name "PB8B/PCLKC5_1/LLC_GPLL0C_IN/ADC_CN3"
						(effects
							(font
								(size 1.27 1.27)
							)
						)
					)
					(number "M7"
						(effects
							(font
								(size 1.27 1.27)
							)
						)
					)
				)
				(pin bidirectional line
					(at 0 -17.78 0)
					(length 3.81)
					(name "PB10A/PCLKT5_2/ADC_CP2/COMP3P"
						(effects
							(font
								(size 1.27 1.27)
							)
						)
					)
					(number "L6"
						(effects
							(font
								(size 1.27 1.27)
							)
						)
					)
				)
				(pin bidirectional line
					(at 0 -20.32 0)
					(length 3.81)
					(name "PB10B/PCLKC5_2/ADC_CN2/COMP3N"
						(effects
							(font
								(size 1.27 1.27)
							)
						)
					)
					(number "K7"
						(effects
							(font
								(size 1.27 1.27)
							)
						)
					)
				)
				(pin bidirectional line
					(at 0 -22.86 0)
					(length 3.81)
					(name "PB12A/PCLKT5_3"
						(effects
							(font
								(size 1.27 1.27)
							)
						)
					)
					(number "P1"
						(effects
							(font
								(size 1.27 1.27)
							)
						)
					)
				)
				(pin bidirectional line
					(at 0 -25.4 0)
					(length 3.81)
					(name "PB12B/PCLKC5_3/VREF5_2"
						(effects
							(font
								(size 1.27 1.27)
							)
						)
					)
					(number "P2"
						(effects
							(font
								(size 1.27 1.27)
							)
						)
					)
				)
			)
			(symbol "CrossLink_LIFCL-40-9BG256C_7_1"
				(rectangle
					(start 3.81 2.54)
					(end 40.64 -68.58)
					(stroke
						(width 0.254)
						(type default)
					)
					(fill
						(type background)
					)
				)
				(text "BANK6"
					(at 39.37 -67.31 0)
					(effects
						(font
							(size 1.27 1.27)
							(thickness 0.15)
						)
						(justify right bottom)
					)
				)
				(pin power_in line
					(at 0 0 0)
					(length 3.81)
					(name "VCCIO6"
						(effects
							(font
								(size 1.27 1.27)
							)
						)
					)
					(number "J4"
						(effects
							(font
								(size 1.27 1.27)
							)
						)
					)
				)
				(pin bidirectional line
					(at 0 -2.54 0)
					(length 3.81)
					(name "PL24A"
						(effects
							(font
								(size 1.27 1.27)
							)
						)
					)
					(number "H6"
						(effects
							(font
								(size 1.27 1.27)
							)
						)
					)
				)
				(pin bidirectional line
					(at 0 -5.08 0)
					(length 3.81)
					(name "PL24B"
						(effects
							(font
								(size 1.27 1.27)
							)
						)
					)
					(number "H5"
						(effects
							(font
								(size 1.27 1.27)
							)
						)
					)
				)
				(pin bidirectional line
					(at 0 -7.62 0)
					(length 3.81)
					(name "PL26A"
						(effects
							(font
								(size 1.27 1.27)
							)
						)
					)
					(number "H4"
						(effects
							(font
								(size 1.27 1.27)
							)
						)
					)
				)
				(pin bidirectional line
					(at 0 -10.16 0)
					(length 3.81)
					(name "PL26B"
						(effects
							(font
								(size 1.27 1.27)
							)
						)
					)
					(number "H3"
						(effects
							(font
								(size 1.27 1.27)
							)
						)
					)
				)
				(pin bidirectional line
					(at 0 -12.7 0)
					(length 3.81)
					(name "PL27A"
						(effects
							(font
								(size 1.27 1.27)
							)
						)
					)
					(number "H1"
						(effects
							(font
								(size 1.27 1.27)
							)
						)
					)
				)
				(pin bidirectional line
					(at 0 -15.24 0)
					(length 3.81)
					(name "PL27B"
						(effects
							(font
								(size 1.27 1.27)
							)
						)
					)
					(number "H2"
						(effects
							(font
								(size 1.27 1.27)
							)
						)
					)
				)
				(pin bidirectional line
					(at 0 -17.78 0)
					(length 3.81)
					(name "PL30A/PCLKT6_0"
						(effects
							(font
								(size 1.27 1.27)
							)
						)
					)
					(number "J6"
						(effects
							(font
								(size 1.27 1.27)
							)
						)
					)
				)
				(pin bidirectional line
					(at 0 -20.32 0)
					(length 3.81)
					(name "PL30B"
						(effects
							(font
								(size 1.27 1.27)
							)
						)
					)
					(number "J5"
						(effects
							(font
								(size 1.27 1.27)
							)
						)
					)
				)
				(pin bidirectional line
					(at 0 -22.86 0)
					(length 3.81)
					(name "PL32A/PCLKT6_1"
						(effects
							(font
								(size 1.27 1.27)
							)
						)
					)
					(number "J1"
						(effects
							(font
								(size 1.27 1.27)
							)
						)
					)
				)
				(pin bidirectional line
					(at 0 -25.4 0)
					(length 3.81)
					(name "PL32B"
						(effects
							(font
								(size 1.27 1.27)
							)
						)
					)
					(number "J2"
						(effects
							(font
								(size 1.27 1.27)
							)
						)
					)
				)
				(pin bidirectional line
					(at 0 -27.94 0)
					(length 3.81)
					(name "PL34A/PCLKT6_2"
						(effects
							(font
								(size 1.27 1.27)
							)
						)
					)
					(number "K1"
						(effects
							(font
								(size 1.27 1.27)
							)
						)
					)
				)
				(pin bidirectional line
					(at 0 -30.48 0)
					(length 3.81)
					(name "PL34B"
						(effects
							(font
								(size 1.27 1.27)
							)
						)
					)
					(number "K2"
						(effects
							(font
								(size 1.27 1.27)
							)
						)
					)
				)
				(pin bidirectional line
					(at 0 -33.02 0)
					(length 3.81)
					(name "PL36A"
						(effects
							(font
								(size 1.27 1.27)
							)
						)
					)
					(number "K4"
						(effects
							(font
								(size 1.27 1.27)
							)
						)
					)
				)
				(pin bidirectional line
					(at 0 -35.56 0)
					(length 3.81)
					(name "PL36B"
						(effects
							(font
								(size 1.27 1.27)
							)
						)
					)
					(number "K3"
						(effects
							(font
								(size 1.27 1.27)
							)
						)
					)
				)
				(pin bidirectional line
					(at 0 -38.1 0)
					(length 3.81)
					(name "PL38A"
						(effects
							(font
								(size 1.27 1.27)
							)
						)
					)
					(number "K6"
						(effects
							(font
								(size 1.27 1.27)
							)
						)
					)
				)
				(pin bidirectional line
					(at 0 -40.64 0)
					(length 3.81)
					(name "PL38B"
						(effects
							(font
								(size 1.27 1.27)
							)
						)
					)
					(number "K5"
						(effects
							(font
								(size 1.27 1.27)
							)
						)
					)
				)
				(pin bidirectional line
					(at 0 -43.18 0)
					(length 3.81)
					(name "PL40A"
						(effects
							(font
								(size 1.27 1.27)
							)
						)
					)
					(number "L1"
						(effects
							(font
								(size 1.27 1.27)
							)
						)
					)
				)
				(pin bidirectional line
					(at 0 -45.72 0)
					(length 3.81)
					(name "PL40B"
						(effects
							(font
								(size 1.27 1.27)
							)
						)
					)
					(number "L2"
						(effects
							(font
								(size 1.27 1.27)
							)
						)
					)
				)
				(pin bidirectional line
					(at 0 -48.26 0)
					(length 3.81)
					(name "PL42A"
						(effects
							(font
								(size 1.27 1.27)
							)
						)
					)
					(number "M1"
						(effects
							(font
								(size 1.27 1.27)
							)
						)
					)
				)
				(pin bidirectional line
					(at 0 -50.8 0)
					(length 3.81)
					(name "PL42B"
						(effects
							(font
								(size 1.27 1.27)
							)
						)
					)
					(number "M2"
						(effects
							(font
								(size 1.27 1.27)
							)
						)
					)
				)
				(pin bidirectional line
					(at 0 -53.34 0)
					(length 3.81)
					(name "PL46A"
						(effects
							(font
								(size 1.27 1.27)
							)
						)
					)
					(number "L4"
						(effects
							(font
								(size 1.27 1.27)
							)
						)
					)
				)
				(pin bidirectional line
					(at 0 -55.88 0)
					(length 3.81)
					(name "PL46B"
						(effects
							(font
								(size 1.27 1.27)
							)
						)
					)
					(number "L5"
						(effects
							(font
								(size 1.27 1.27)
							)
						)
					)
				)
				(pin bidirectional line
					(at 0 -58.42 0)
					(length 3.81)
					(name "PL47A"
						(effects
							(font
								(size 1.27 1.27)
							)
						)
					)
					(number "M3"
						(effects
							(font
								(size 1.27 1.27)
							)
						)
					)
				)
				(pin bidirectional line
					(at 0 -60.96 0)
					(length 3.81)
					(name "PL47B"
						(effects
							(font
								(size 1.27 1.27)
							)
						)
					)
					(number "L3"
						(effects
							(font
								(size 1.27 1.27)
							)
						)
					)
				)
				(pin bidirectional line
					(at 0 -63.5 0)
					(length 3.81)
					(name "PL49A"
						(effects
							(font
								(size 1.27 1.27)
							)
						)
					)
					(number "N2"
						(effects
							(font
								(size 1.27 1.27)
							)
						)
					)
				)
				(pin bidirectional line
					(at 0 -66.04 0)
					(length 3.81)
					(name "PL49B"
						(effects
							(font
								(size 1.27 1.27)
							)
						)
					)
					(number "N1"
						(effects
							(font
								(size 1.27 1.27)
							)
						)
					)
				)
			)
			(symbol "CrossLink_LIFCL-40-9BG256C_8_1"
				(rectangle
					(start 3.81 -30.48)
					(end 41.91 2.54)
					(stroke
						(width 0.254)
						(type default)
					)
					(fill
						(type background)
					)
				)
				(text "BANK7"
					(at 40.64 -29.21 0)
					(effects
						(font
							(size 1.27 1.27)
							(thickness 0.15)
						)
						(justify right bottom)
					)
				)
				(pin power_in line
					(at 0 0 0)
					(length 3.81)
					(name "VCCIO7"
						(effects
							(font
								(size 1.27 1.27)
							)
						)
					)
					(number "F5"
						(effects
							(font
								(size 1.27 1.27)
							)
						)
					)
				)
				(pin bidirectional line
					(at 0 -2.54 0)
					(length 3.81)
					(name "PL3A/ULC_GPLL0T_IN"
						(effects
							(font
								(size 1.27 1.27)
							)
						)
					)
					(number "D4"
						(effects
							(font
								(size 1.27 1.27)
							)
						)
					)
				)
				(pin bidirectional line
					(at 0 -5.08 0)
					(length 3.81)
					(name "PL3B/ULC_GPLL0C_IN"
						(effects
							(font
								(size 1.27 1.27)
							)
						)
					)
					(number "D5"
						(effects
							(font
								(size 1.27 1.27)
							)
						)
					)
				)
				(pin bidirectional line
					(at 0 -7.62 0)
					(length 3.81)
					(name "PL4A"
						(effects
							(font
								(size 1.27 1.27)
							)
						)
					)
					(number "D6"
						(effects
							(font
								(size 1.27 1.27)
							)
						)
					)
				)
				(pin bidirectional line
					(at 0 -10.16 0)
					(length 3.81)
					(name "PL4B"
						(effects
							(font
								(size 1.27 1.27)
							)
						)
					)
					(number "E6"
						(effects
							(font
								(size 1.27 1.27)
							)
						)
					)
				)
				(pin bidirectional line
					(at 0 -12.7 0)
					(length 3.81)
					(name "PL6A"
						(effects
							(font
								(size 1.27 1.27)
							)
						)
					)
					(number "E4"
						(effects
							(font
								(size 1.27 1.27)
							)
						)
					)
				)
				(pin bidirectional line
					(at 0 -15.24 0)
					(length 3.81)
					(name "PL6B"
						(effects
							(font
								(size 1.27 1.27)
							)
						)
					)
					(number "E5"
						(effects
							(font
								(size 1.27 1.27)
							)
						)
					)
				)
				(pin bidirectional line
					(at 0 -17.78 0)
					(length 3.81)
					(name "PL17A/PCLKT7_2"
						(effects
							(font
								(size 1.27 1.27)
							)
						)
					)
					(number "F6"
						(effects
							(font
								(size 1.27 1.27)
							)
						)
					)
				)
				(pin bidirectional line
					(at 0 -20.32 0)
					(length 3.81)
					(name "PL17B"
						(effects
							(font
								(size 1.27 1.27)
							)
						)
					)
					(number "G6"
						(effects
							(font
								(size 1.27 1.27)
							)
						)
					)
				)
				(pin bidirectional line
					(at 0 -22.86 0)
					(length 3.81)
					(name "PL19A/PCLKT7_1"
						(effects
							(font
								(size 1.27 1.27)
							)
						)
					)
					(number "F4"
						(effects
							(font
								(size 1.27 1.27)
							)
						)
					)
				)
				(pin bidirectional line
					(at 0 -25.4 0)
					(length 3.81)
					(name "PL19B"
						(effects
							(font
								(size 1.27 1.27)
							)
						)
					)
					(number "G4"
						(effects
							(font
								(size 1.27 1.27)
							)
						)
					)
				)
				(pin bidirectional line
					(at 0 -27.94 0)
					(length 3.81)
					(name "PL20A/PCLKT7_0"
						(effects
							(font
								(size 1.27 1.27)
							)
						)
					)
					(number "G3"
						(effects
							(font
								(size 1.27 1.27)
							)
						)
					)
				)
			)
			(symbol "CrossLink_LIFCL-40-9BG256C_9_1"
				(rectangle
					(start 3.81 2.54)
					(end 25.4 -30.48)
					(stroke
						(width 0.254)
						(type default)
					)
					(fill
						(type background)
					)
				)
				(text "PHY0"
					(at 24.13 -29.21 0)
					(effects
						(font
							(size 1.27 1.27)
							(thickness 0.15)
						)
						(justify right bottom)
					)
				)
				(pin bidirectional clock
					(at 0 0 0)
					(length 3.81)
					(name "DPHY0_CK+"
						(effects
							(font
								(size 1.27 1.27)
							)
						)
					)
					(number "D1"
						(effects
							(font
								(size 1.27 1.27)
							)
						)
					)
				)
				(pin bidirectional clock
					(at 0 -2.54 0)
					(length 3.81)
					(name "DPHY0_CK-"
						(effects
							(font
								(size 1.27 1.27)
							)
						)
					)
					(number "D2"
						(effects
							(font
								(size 1.27 1.27)
							)
						)
					)
				)
				(pin bidirectional line
					(at 0 -6.35 0)
					(length 3.81)
					(name "DPHY0_D0+"
						(effects
							(font
								(size 1.27 1.27)
							)
						)
					)
					(number "E1"
						(effects
							(font
								(size 1.27 1.27)
							)
						)
					)
				)
				(pin bidirectional line
					(at 0 -8.89 0)
					(length 3.81)
					(name "DPHY0_D0-"
						(effects
							(font
								(size 1.27 1.27)
							)
						)
					)
					(number "E2"
						(effects
							(font
								(size 1.27 1.27)
							)
						)
					)
				)
				(pin bidirectional line
					(at 0 -12.7 0)
					(length 3.81)
					(name "DPHY0_D1+"
						(effects
							(font
								(size 1.27 1.27)
							)
						)
					)
					(number "C1"
						(effects
							(font
								(size 1.27 1.27)
							)
						)
					)
				)
				(pin bidirectional line
					(at 0 -15.24 0)
					(length 3.81)
					(name "DPHY0_D1-"
						(effects
							(font
								(size 1.27 1.27)
							)
						)
					)
					(number "C2"
						(effects
							(font
								(size 1.27 1.27)
							)
						)
					)
				)
				(pin bidirectional line
					(at 0 -19.05 0)
					(length 3.81)
					(name "DPHY0_D2+"
						(effects
							(font
								(size 1.27 1.27)
							)
						)
					)
					(number "F1"
						(effects
							(font
								(size 1.27 1.27)
							)
						)
					)
				)
				(pin bidirectional line
					(at 0 -21.59 0)
					(length 3.81)
					(name "DPHY0_D2-"
						(effects
							(font
								(size 1.27 1.27)
							)
						)
					)
					(number "F2"
						(effects
							(font
								(size 1.27 1.27)
							)
						)
					)
				)
				(pin bidirectional line
					(at 0 -25.4 0)
					(length 3.81)
					(name "DPHY0_D3+"
						(effects
							(font
								(size 1.27 1.27)
							)
						)
					)
					(number "B1"
						(effects
							(font
								(size 1.27 1.27)
							)
						)
					)
				)
				(pin bidirectional line
					(at 0 -27.94 0)
					(length 3.81)
					(name "DPHY0_D3-"
						(effects
							(font
								(size 1.27 1.27)
							)
						)
					)
					(number "B2"
						(effects
							(font
								(size 1.27 1.27)
							)
						)
					)
				)
			)
			(symbol "CrossLink_LIFCL-40-9BG256C_10_1"
				(rectangle
					(start 3.81 2.54)
					(end 25.4 -30.48)
					(stroke
						(width 0.254)
						(type default)
					)
					(fill
						(type background)
					)
				)
				(text "PHY1"
					(at 24.13 -29.21 0)
					(effects
						(font
							(size 1.27 1.27)
							(thickness 0.15)
						)
						(justify right bottom)
					)
				)
				(pin bidirectional clock
					(at 0 0 0)
					(length 3.81)
					(name "DPHY1_CK+"
						(effects
							(font
								(size 1.27 1.27)
							)
						)
					)
					(number "A5"
						(effects
							(font
								(size 1.27 1.27)
							)
						)
					)
				)
				(pin bidirectional clock
					(at 0 -2.54 0)
					(length 3.81)
					(name "DPHY1_CK-"
						(effects
							(font
								(size 1.27 1.27)
							)
						)
					)
					(number "B5"
						(effects
							(font
								(size 1.27 1.27)
							)
						)
					)
				)
				(pin bidirectional line
					(at 0 -6.35 0)
					(length 3.81)
					(name "DPHY1_D0+"
						(effects
							(font
								(size 1.27 1.27)
							)
						)
					)
					(number "A4"
						(effects
							(font
								(size 1.27 1.27)
							)
						)
					)
				)
				(pin bidirectional line
					(at 0 -8.89 0)
					(length 3.81)
					(name "DPHY1_D0-"
						(effects
							(font
								(size 1.27 1.27)
							)
						)
					)
					(number "B4"
						(effects
							(font
								(size 1.27 1.27)
							)
						)
					)
				)
				(pin bidirectional line
					(at 0 -12.7 0)
					(length 3.81)
					(name "DPHY1_D1+"
						(effects
							(font
								(size 1.27 1.27)
							)
						)
					)
					(number "A6"
						(effects
							(font
								(size 1.27 1.27)
							)
						)
					)
				)
				(pin bidirectional line
					(at 0 -15.24 0)
					(length 3.81)
					(name "DPHY1_D1-"
						(effects
							(font
								(size 1.27 1.27)
							)
						)
					)
					(number "B6"
						(effects
							(font
								(size 1.27 1.27)
							)
						)
					)
				)
				(pin bidirectional line
					(at 0 -19.05 0)
					(length 3.81)
					(name "DPHY1_D2+"
						(effects
							(font
								(size 1.27 1.27)
							)
						)
					)
					(number "A3"
						(effects
							(font
								(size 1.27 1.27)
							)
						)
					)
				)
				(pin bidirectional line
					(at 0 -21.59 0)
					(length 3.81)
					(name "DPHY1_D2-"
						(effects
							(font
								(size 1.27 1.27)
							)
						)
					)
					(number "B3"
						(effects
							(font
								(size 1.27 1.27)
							)
						)
					)
				)
				(pin bidirectional line
					(at 0 -25.4 0)
					(length 3.81)
					(name "DPHY1_D3+"
						(effects
							(font
								(size 1.27 1.27)
							)
						)
					)
					(number "A7"
						(effects
							(font
								(size 1.27 1.27)
							)
						)
					)
				)
				(pin bidirectional line
					(at 0 -27.94 0)
					(length 3.81)
					(name "DPHY1_D3-"
						(effects
							(font
								(size 1.27 1.27)
							)
						)
					)
					(number "B7"
						(effects
							(font
								(size 1.27 1.27)
							)
						)
					)
				)
			)
			(symbol "CrossLink_LIFCL-40-9BG256C_11_1"
				(rectangle
					(start 3.81 2.54)
					(end 25.4 -25.4)
					(stroke
						(width 0.254)
						(type default)
					)
					(fill
						(type background)
					)
				)
				(text "ADC"
					(at 24.13 -24.13 0)
					(effects
						(font
							(size 1.27 1.27)
							(thickness 0.15)
						)
						(justify right bottom)
					)
				)
				(pin power_in line
					(at 0 0 0)
					(length 3.81)
					(name "VCCADC18"
						(effects
							(font
								(size 1.27 1.27)
							)
						)
					)
					(number "L14"
						(effects
							(font
								(size 1.27 1.27)
							)
						)
					)
				)
				(pin passive line
					(at 0 -3.81 0)
					(length 3.81)
					(name "ADC_D0+"
						(effects
							(font
								(size 1.27 1.27)
							)
						)
					)
					(number "K14"
						(effects
							(font
								(size 1.27 1.27)
							)
						)
					)
				)
				(pin passive line
					(at 0 -6.35 0)
					(length 3.81)
					(name "ADC_D0-"
						(effects
							(font
								(size 1.27 1.27)
							)
						)
					)
					(number "K13"
						(effects
							(font
								(size 1.27 1.27)
							)
						)
					)
				)
				(pin passive line
					(at 0 -10.16 0)
					(length 3.81)
					(name "ADC_D1+"
						(effects
							(font
								(size 1.27 1.27)
							)
						)
					)
					(number "K15"
						(effects
							(font
								(size 1.27 1.27)
							)
						)
					)
				)
				(pin passive line
					(at 0 -12.7 0)
					(length 3.81)
					(name "ADC_D1-"
						(effects
							(font
								(size 1.27 1.27)
							)
						)
					)
					(number "K16"
						(effects
							(font
								(size 1.27 1.27)
							)
						)
					)
				)
				(pin passive line
					(at 0 -16.51 0)
					(length 3.81)
					(name "ADC_REFP0"
						(effects
							(font
								(size 1.27 1.27)
							)
						)
					)
					(number "L15"
						(effects
							(font
								(size 1.27 1.27)
							)
						)
					)
				)
				(pin passive line
					(at 0 -19.05 0)
					(length 3.81)
					(name "ADC_REFP1"
						(effects
							(font
								(size 1.27 1.27)
							)
						)
					)
					(number "L16"
						(effects
							(font
								(size 1.27 1.27)
							)
						)
					)
				)
				(pin power_in line
					(at 0 -22.86 0)
					(length 3.81)
					(name "VSSADC"
						(effects
							(font
								(size 1.27 1.27)
							)
						)
					)
					(number "L13"
						(effects
							(font
								(size 1.27 1.27)
							)
						)
					)
				)
			)
			(symbol "CrossLink_LIFCL-40-9BG256C_12_1"
				(rectangle
					(start 3.81 2.54)
					(end 25.4 -24.13)
					(stroke
						(width 0.254)
						(type default)
					)
					(fill
						(type background)
					)
				)
				(text "SDO"
					(at 24.13 -22.86 0)
					(effects
						(font
							(size 1.27 1.27)
							(thickness 0.15)
						)
						(justify right bottom)
					)
				)
				(pin bidirectional line
					(at 0 0 0)
					(length 3.81)
					(name "SD_REFCLK+"
						(effects
							(font
								(size 1.27 1.27)
							)
						)
					)
					(number "A9"
						(effects
							(font
								(size 1.27 1.27)
							)
						)
					)
				)
				(pin bidirectional line
					(at 0 -2.54 0)
					(length 3.81)
					(name "SD_REFCLK-"
						(effects
							(font
								(size 1.27 1.27)
							)
						)
					)
					(number "B9"
						(effects
							(font
								(size 1.27 1.27)
							)
						)
					)
				)
				(pin output line
					(at 0 -6.35 0)
					(length 3.81)
					(name "SD0_TXD+"
						(effects
							(font
								(size 1.27 1.27)
							)
						)
					)
					(number "A12"
						(effects
							(font
								(size 1.27 1.27)
							)
						)
					)
				)
				(pin output line
					(at 0 -8.89 0)
					(length 3.81)
					(name "SD0_TXD-"
						(effects
							(font
								(size 1.27 1.27)
							)
						)
					)
					(number "A11"
						(effects
							(font
								(size 1.27 1.27)
							)
						)
					)
				)
				(pin input line
					(at 0 -12.7 0)
					(length 3.81)
					(name "SD0_RXD+"
						(effects
							(font
								(size 1.27 1.27)
							)
						)
					)
					(number "A15"
						(effects
							(font
								(size 1.27 1.27)
							)
						)
					)
				)
				(pin input line
					(at 0 -15.24 0)
					(length 3.81)
					(name "SD0_RXD-"
						(effects
							(font
								(size 1.27 1.27)
							)
						)
					)
					(number "A14"
						(effects
							(font
								(size 1.27 1.27)
							)
						)
					)
				)
				(pin input line
					(at 0 -19.05 0)
					(length 3.81)
					(name "SD0_REFRET"
						(effects
							(font
								(size 1.27 1.27)
							)
						)
					)
					(number "B12"
						(effects
							(font
								(size 1.27 1.27)
							)
						)
					)
				)
				(pin input line
					(at 0 -21.59 0)
					(length 3.81)
					(name "SD0_REXT"
						(effects
							(font
								(size 1.27 1.27)
							)
						)
					)
					(number "C11"
						(effects
							(font
								(size 1.27 1.27)
							)
						)
					)
				)
			)
			(symbol "CrossLink_LIFCL-40-9BG256C_13_1"
				(rectangle
					(start 3.81 2.54)
					(end 29.21 -48.26)
					(stroke
						(width 0.254)
						(type default)
					)
					(fill
						(type background)
					)
				)
				(pin power_in line
					(at 0 0 0)
					(length 3.81)
					(name "VCC"
						(effects
							(font
								(size 1.27 1.27)
							)
						)
					)
					(number "D7"
						(effects
							(font
								(size 1.27 1.27)
							)
						)
					)
				)
				(pin passive line
					(at 0 0 0)
					(length 3.81)
					(hide yes)
					(name "VCC"
						(effects
							(font
								(size 1.27 1.27)
							)
						)
					)
					(number "D9"
						(effects
							(font
								(size 1.27 1.27)
							)
						)
					)
				)
				(pin passive line
					(at 0 0 0)
					(length 3.81)
					(hide yes)
					(name "VCC"
						(effects
							(font
								(size 1.27 1.27)
							)
						)
					)
					(number "H7"
						(effects
							(font
								(size 1.27 1.27)
							)
						)
					)
				)
				(pin passive line
					(at 0 0 0)
					(length 3.81)
					(hide yes)
					(name "VCC"
						(effects
							(font
								(size 1.27 1.27)
							)
						)
					)
					(number "J10"
						(effects
							(font
								(size 1.27 1.27)
							)
						)
					)
				)
				(pin power_in line
					(at 0 -3.81 0)
					(length 3.81)
					(name "VCCECLK"
						(effects
							(font
								(size 1.27 1.27)
							)
						)
					)
					(number "K9"
						(effects
							(font
								(size 1.27 1.27)
							)
						)
					)
				)
				(pin power_in line
					(at 0 -7.62 0)
					(length 3.81)
					(name "VCCAUX"
						(effects
							(font
								(size 1.27 1.27)
							)
						)
					)
					(number "F8"
						(effects
							(font
								(size 1.27 1.27)
							)
						)
					)
				)
				(pin passive line
					(at 0 -7.62 0)
					(length 3.81)
					(hide yes)
					(name "VCCAUX"
						(effects
							(font
								(size 1.27 1.27)
							)
						)
					)
					(number "G7"
						(effects
							(font
								(size 1.27 1.27)
							)
						)
					)
				)
				(pin power_in line
					(at 0 -10.16 0)
					(length 3.81)
					(name "VCCAUXA"
						(effects
							(font
								(size 1.27 1.27)
							)
						)
					)
					(number "F7"
						(effects
							(font
								(size 1.27 1.27)
							)
						)
					)
				)
				(pin power_in line
					(at 0 -12.7 0)
					(length 3.81)
					(name "VCCAUXH3"
						(effects
							(font
								(size 1.27 1.27)
							)
						)
					)
					(number "K10"
						(effects
							(font
								(size 1.27 1.27)
							)
						)
					)
				)
				(pin power_in line
					(at 0 -15.24 0)
					(length 3.81)
					(name "VCCAUXH4"
						(effects
							(font
								(size 1.27 1.27)
							)
						)
					)
					(number "K8"
						(effects
							(font
								(size 1.27 1.27)
							)
						)
					)
				)
				(pin power_in line
					(at 0 -17.78 0)
					(length 3.81)
					(name "VCCAUXH5"
						(effects
							(font
								(size 1.27 1.27)
							)
						)
					)
					(number "M6"
						(effects
							(font
								(size 1.27 1.27)
							)
						)
					)
				)
				(pin power_in line
					(at 0 -21.59 0)
					(length 3.81)
					(name "VCCDPHY0"
						(effects
							(font
								(size 1.27 1.27)
							)
						)
					)
					(number "C4"
						(effects
							(font
								(size 1.27 1.27)
							)
						)
					)
				)
				(pin power_in line
					(at 0 -24.13 0)
					(length 3.81)
					(name "VCCDPHY1"
						(effects
							(font
								(size 1.27 1.27)
							)
						)
					)
					(number "C7"
						(effects
							(font
								(size 1.27 1.27)
							)
						)
					)
				)
				(pin power_in line
					(at 0 -27.94 0)
					(length 3.81)
					(name "VCCADPHY0"
						(effects
							(font
								(size 1.27 1.27)
							)
						)
					)
					(number "E3"
						(effects
							(font
								(size 1.27 1.27)
							)
						)
					)
				)
				(pin power_in line
					(at 0 -30.48 0)
					(length 3.81)
					(name "VCCADPHY1"
						(effects
							(font
								(size 1.27 1.27)
							)
						)
					)
					(number "C8"
						(effects
							(font
								(size 1.27 1.27)
							)
						)
					)
				)
				(pin power_in line
					(at 0 -34.29 0)
					(length 3.81)
					(name "VCCPLLDPHY0"
						(effects
							(font
								(size 1.27 1.27)
							)
						)
					)
					(number "A2"
						(effects
							(font
								(size 1.27 1.27)
							)
						)
					)
				)
				(pin power_in line
					(at 0 -36.83 0)
					(length 3.81)
					(name "VCCPLLDPHY1"
						(effects
							(font
								(size 1.27 1.27)
							)
						)
					)
					(number "C5"
						(effects
							(font
								(size 1.27 1.27)
							)
						)
					)
				)
				(pin power_in line
					(at 0 -40.64 0)
					(length 3.81)
					(name "VCCAUXSD"
						(effects
							(font
								(size 1.27 1.27)
							)
						)
					)
					(number "B11"
						(effects
							(font
								(size 1.27 1.27)
							)
						)
					)
				)
				(pin power_in line
					(at 0 -43.18 0)
					(length 3.81)
					(name "VCCSD0"
						(effects
							(font
								(size 1.27 1.27)
							)
						)
					)
					(number "B15"
						(effects
							(font
								(size 1.27 1.27)
							)
						)
					)
				)
				(pin power_in line
					(at 0 -45.72 0)
					(length 3.81)
					(name "VCCPLLSD0"
						(effects
							(font
								(size 1.27 1.27)
							)
						)
					)
					(number "B13"
						(effects
							(font
								(size 1.27 1.27)
							)
						)
					)
				)
				(pin power_in line
					(at 33.02 0 180)
					(length 3.81)
					(name "VSSADPHY"
						(effects
							(font
								(size 1.27 1.27)
							)
						)
					)
					(number "A1"
						(effects
							(font
								(size 1.27 1.27)
							)
						)
					)
				)
				(pin passive line
					(at 33.02 0 180)
					(length 3.81)
					(hide yes)
					(name "VSSADPHY"
						(effects
							(font
								(size 1.27 1.27)
							)
						)
					)
					(number "A8"
						(effects
							(font
								(size 1.27 1.27)
							)
						)
					)
				)
				(pin passive line
					(at 33.02 0 180)
					(length 3.81)
					(hide yes)
					(name "VSSADPHY"
						(effects
							(font
								(size 1.27 1.27)
							)
						)
					)
					(number "B8"
						(effects
							(font
								(size 1.27 1.27)
							)
						)
					)
				)
				(pin passive line
					(at 33.02 0 180)
					(length 3.81)
					(hide yes)
					(name "VSSADPHY"
						(effects
							(font
								(size 1.27 1.27)
							)
						)
					)
					(number "C3"
						(effects
							(font
								(size 1.27 1.27)
							)
						)
					)
				)
				(pin passive line
					(at 33.02 0 180)
					(length 3.81)
					(hide yes)
					(name "VSSADPHY"
						(effects
							(font
								(size 1.27 1.27)
							)
						)
					)
					(number "C6"
						(effects
							(font
								(size 1.27 1.27)
							)
						)
					)
				)
				(pin passive line
					(at 33.02 0 180)
					(length 3.81)
					(hide yes)
					(name "VSSADPHY"
						(effects
							(font
								(size 1.27 1.27)
							)
						)
					)
					(number "D3"
						(effects
							(font
								(size 1.27 1.27)
							)
						)
					)
				)
				(pin passive line
					(at 33.02 0 180)
					(length 3.81)
					(hide yes)
					(name "VSSADPHY"
						(effects
							(font
								(size 1.27 1.27)
							)
						)
					)
					(number "F3"
						(effects
							(font
								(size 1.27 1.27)
							)
						)
					)
				)
				(pin passive line
					(at 33.02 0 180)
					(length 3.81)
					(hide yes)
					(name "VSSADPHY"
						(effects
							(font
								(size 1.27 1.27)
							)
						)
					)
					(number "G1"
						(effects
							(font
								(size 1.27 1.27)
							)
						)
					)
				)
				(pin power_in line
					(at 33.02 -3.81 180)
					(length 3.81)
					(name "VSSSD"
						(effects
							(font
								(size 1.27 1.27)
							)
						)
					)
					(number "A10"
						(effects
							(font
								(size 1.27 1.27)
							)
						)
					)
				)
				(pin passive line
					(at 33.02 -3.81 180)
					(length 3.81)
					(hide yes)
					(name "VSSSD"
						(effects
							(font
								(size 1.27 1.27)
							)
						)
					)
					(number "A13"
						(effects
							(font
								(size 1.27 1.27)
							)
						)
					)
				)
				(pin passive line
					(at 33.02 -3.81 180)
					(length 3.81)
					(hide yes)
					(name "VSSSD"
						(effects
							(font
								(size 1.27 1.27)
							)
						)
					)
					(number "A16"
						(effects
							(font
								(size 1.27 1.27)
							)
						)
					)
				)
				(pin passive line
					(at 33.02 -3.81 180)
					(length 3.81)
					(hide yes)
					(name "VSSSD"
						(effects
							(font
								(size 1.27 1.27)
							)
						)
					)
					(number "B10"
						(effects
							(font
								(size 1.27 1.27)
							)
						)
					)
				)
				(pin passive line
					(at 33.02 -3.81 180)
					(length 3.81)
					(hide yes)
					(name "VSSSD"
						(effects
							(font
								(size 1.27 1.27)
							)
						)
					)
					(number "B14"
						(effects
							(font
								(size 1.27 1.27)
							)
						)
					)
				)
				(pin power_in line
					(at 33.02 -7.62 180)
					(length 3.81)
					(name "VSS"
						(effects
							(font
								(size 1.27 1.27)
							)
						)
					)
					(number "C10"
						(effects
							(font
								(size 1.27 1.27)
							)
						)
					)
				)
				(pin passive line
					(at 33.02 -7.62 180)
					(length 3.81)
					(hide yes)
					(name "VSS"
						(effects
							(font
								(size 1.27 1.27)
							)
						)
					)
					(number "C9"
						(effects
							(font
								(size 1.27 1.27)
							)
						)
					)
				)
				(pin passive line
					(at 33.02 -7.62 180)
					(length 3.81)
					(hide yes)
					(name "VSS"
						(effects
							(font
								(size 1.27 1.27)
							)
						)
					)
					(number "D14"
						(effects
							(font
								(size 1.27 1.27)
							)
						)
					)
				)
				(pin passive line
					(at 33.02 -7.62 180)
					(length 3.81)
					(hide yes)
					(name "VSS"
						(effects
							(font
								(size 1.27 1.27)
							)
						)
					)
					(number "D8"
						(effects
							(font
								(size 1.27 1.27)
							)
						)
					)
				)
				(pin passive line
					(at 33.02 -7.62 180)
					(length 3.81)
					(hide yes)
					(name "VSS"
						(effects
							(font
								(size 1.27 1.27)
							)
						)
					)
					(number "E7"
						(effects
							(font
								(size 1.27 1.27)
							)
						)
					)
				)
				(pin passive line
					(at 33.02 -7.62 180)
					(length 3.81)
					(hide yes)
					(name "VSS"
						(effects
							(font
								(size 1.27 1.27)
							)
						)
					)
					(number "E8"
						(effects
							(font
								(size 1.27 1.27)
							)
						)
					)
				)
				(pin passive line
					(at 33.02 -7.62 180)
					(length 3.81)
					(hide yes)
					(name "VSS"
						(effects
							(font
								(size 1.27 1.27)
							)
						)
					)
					(number "F12"
						(effects
							(font
								(size 1.27 1.27)
							)
						)
					)
				)
				(pin passive line
					(at 33.02 -7.62 180)
					(length 3.81)
					(hide yes)
					(name "VSS"
						(effects
							(font
								(size 1.27 1.27)
							)
						)
					)
					(number "G2"
						(effects
							(font
								(size 1.27 1.27)
							)
						)
					)
				)
				(pin passive line
					(at 33.02 -7.62 180)
					(length 3.81)
					(hide yes)
					(name "VSS"
						(effects
							(font
								(size 1.27 1.27)
							)
						)
					)
					(number "G5"
						(effects
							(font
								(size 1.27 1.27)
							)
						)
					)
				)
				(pin passive line
					(at 33.02 -7.62 180)
					(length 3.81)
					(hide yes)
					(name "VSS"
						(effects
							(font
								(size 1.27 1.27)
							)
						)
					)
					(number "G8"
						(effects
							(font
								(size 1.27 1.27)
							)
						)
					)
				)
				(pin passive line
					(at 33.02 -7.62 180)
					(length 3.81)
					(hide yes)
					(name "VSS"
						(effects
							(font
								(size 1.27 1.27)
							)
						)
					)
					(number "H8"
						(effects
							(font
								(size 1.27 1.27)
							)
						)
					)
				)
				(pin passive line
					(at 33.02 -7.62 180)
					(length 3.81)
					(hide yes)
					(name "VSS"
						(effects
							(font
								(size 1.27 1.27)
							)
						)
					)
					(number "H9"
						(effects
							(font
								(size 1.27 1.27)
							)
						)
					)
				)
				(pin passive line
					(at 33.02 -7.62 180)
					(length 3.81)
					(hide yes)
					(name "VSS"
						(effects
							(font
								(size 1.27 1.27)
							)
						)
					)
					(number "J14"
						(effects
							(font
								(size 1.27 1.27)
							)
						)
					)
				)
				(pin passive line
					(at 33.02 -7.62 180)
					(length 3.81)
					(hide yes)
					(name "VSS"
						(effects
							(font
								(size 1.27 1.27)
							)
						)
					)
					(number "J3"
						(effects
							(font
								(size 1.27 1.27)
							)
						)
					)
				)
				(pin passive line
					(at 33.02 -7.62 180)
					(length 3.81)
					(hide yes)
					(name "VSS"
						(effects
							(font
								(size 1.27 1.27)
							)
						)
					)
					(number "J7"
						(effects
							(font
								(size 1.27 1.27)
							)
						)
					)
				)
				(pin passive line
					(at 33.02 -7.62 180)
					(length 3.81)
					(hide yes)
					(name "VSS"
						(effects
							(font
								(size 1.27 1.27)
							)
						)
					)
					(number "J8"
						(effects
							(font
								(size 1.27 1.27)
							)
						)
					)
				)
				(pin passive line
					(at 33.02 -7.62 180)
					(length 3.81)
					(hide yes)
					(name "VSS"
						(effects
							(font
								(size 1.27 1.27)
							)
						)
					)
					(number "J9"
						(effects
							(font
								(size 1.27 1.27)
							)
						)
					)
				)
				(pin passive line
					(at 33.02 -7.62 180)
					(length 3.81)
					(hide yes)
					(name "VSS"
						(effects
							(font
								(size 1.27 1.27)
							)
						)
					)
					(number "M5"
						(effects
							(font
								(size 1.27 1.27)
							)
						)
					)
				)
				(pin passive line
					(at 33.02 -7.62 180)
					(length 3.81)
					(hide yes)
					(name "VSS"
						(effects
							(font
								(size 1.27 1.27)
							)
						)
					)
					(number "N7"
						(effects
							(font
								(size 1.27 1.27)
							)
						)
					)
				)
				(pin passive line
					(at 33.02 -7.62 180)
					(length 3.81)
					(hide yes)
					(name "VSS"
						(effects
							(font
								(size 1.27 1.27)
							)
						)
					)
					(number "P13"
						(effects
							(font
								(size 1.27 1.27)
							)
						)
					)
				)
				(pin passive line
					(at 33.02 -7.62 180)
					(length 3.81)
					(hide yes)
					(name "VSS"
						(effects
							(font
								(size 1.27 1.27)
							)
						)
					)
					(number "T1"
						(effects
							(font
								(size 1.27 1.27)
							)
						)
					)
				)
				(pin passive line
					(at 33.02 -7.62 180)
					(length 3.81)
					(hide yes)
					(name "VSS"
						(effects
							(font
								(size 1.27 1.27)
							)
						)
					)
					(number "T16"
						(effects
							(font
								(size 1.27 1.27)
							)
						)
					)
				)
			)
		)
	(symbol "antmicroFerriteBeadsandChips:FB_120Z_2A_Murata-BLM18PG_0603"
			(pin_numbers
				(hide yes)
			)
			(pin_names
				(hide yes)
			)
			(exclude_from_sim no)
			(in_bom yes)
			(on_board yes)
			(property "Reference" "FB"
				(at 15.24 0 0)
				(effects
					(font
						(size 1.27 1.27)
						(thickness 0.15)
					)
					(justify left bottom)
				)
			)
			(property "Value" "FB_120Z_2A_Murata-BLM18PG_0603"
				(at 15.24 -2.54 0)
				(effects
					(font
						(size 1.27 1.27)
						(thickness 0.15)
					)
					(justify left bottom)
					(hide yes)
				)
			)
			(property "Footprint" "antmicro-footprints:FB_0603_1608Metric"
				(at 15.24 -7.62 0)
				(effects
					(font
						(size 1.27 1.27)
						(thickness 0.15)
					)
					(justify left bottom)
					(hide yes)
				)
			)
			(property "Datasheet" "https://www.murata.com/en-us/products/productdata/8796738650142/ENFA0003.pdf"
				(at 15.24 -10.16 0)
				(effects
					(font
						(size 1.27 1.27)
						(thickness 0.15)
					)
					(justify left bottom)
					(hide yes)
				)
			)
			(property "Description" "Ferrite Bead, 0603 [1608 Metric], 120 ohm, 2 A, BLM18P, 0.05 ohm, ± 25%, DC power line"
				(at 15.24 -22.86 0)
				(effects
					(font
						(size 1.27 1.27)
					)
					(justify left bottom)
					(hide yes)
				)
			)
			(property "Val" "120Z/2A"
				(at 15.24 -5.08 0)
				(effects
					(font
						(size 1.27 1.27)
					)
					(justify left bottom)
				)
			)
			(property "MPN" "BLM18PG121SN1D"
				(at 15.24 -12.7 0)
				(effects
					(font
						(size 1.27 1.27)
						(thickness 0.15)
					)
					(justify left bottom)
					(hide yes)
				)
			)
			(property "Manufacturer" "Murata"
				(at 15.24 -15.24 0)
				(effects
					(font
						(size 1.27 1.27)
						(thickness 0.15)
					)
					(justify left bottom)
					(hide yes)
				)
			)
			(property "Current" ""
				(at 20.32 -22.86 0)
				(effects
					(font
						(size 1.27 1.27)
						(thickness 0.15)
					)
					(justify left bottom)
					(hide yes)
				)
			)
			(property "Author" "Antmicro"
				(at 15.24 -17.78 0)
				(effects
					(font
						(size 1.27 1.27)
						(thickness 0.15)
					)
					(justify left bottom)
					(hide yes)
				)
			)
			(property "License" "Apache-2.0"
				(at 15.24 -20.32 0)
				(effects
					(font
						(size 1.27 1.27)
						(thickness 0.15)
					)
					(justify left bottom)
					(hide yes)
				)
			)
			(property "ki_keywords" "0603, SMT, FERRITE BEAD, PASSIVE"
				(at 0 0 0)
				(effects
					(font
						(size 1.27 1.27)
					)
					(hide yes)
				)
			)
			(symbol "FB_120Z_2A_Murata-BLM18PG_0603_0_1"
				(polyline
					(pts
						(xy 1.651 0) (xy 1.2446 0)
					)
					(stroke
						(width 0)
						(type default)
					)
					(fill
						(type none)
					)
				)
				(polyline
					(pts
						(xy 2.2606 -1.8288) (xy 1.0414 -1.1176) (xy 2.7432 1.8288) (xy 3.9624 1.1176) (xy 2.2606 -1.8288)
					)
					(stroke
						(width 0)
						(type default)
					)
					(fill
						(type none)
					)
				)
				(polyline
					(pts
						(xy 3.81 0) (xy 3.3274 0)
					)
					(stroke
						(width 0)
						(type default)
					)
					(fill
						(type none)
					)
				)
			)
			(symbol "FB_120Z_2A_Murata-BLM18PG_0603_1_1"
				(pin passive line
					(at 0 0 0)
					(length 1.27)
					(name "~"
						(effects
							(font
								(size 1.27 1.27)
							)
						)
					)
					(number "1"
						(effects
							(font
								(size 1.27 1.27)
							)
						)
					)
				)
				(pin passive line
					(at 5.08 0 180)
					(length 1.27)
					(name "~"
						(effects
							(font
								(size 1.27 1.27)
							)
						)
					)
					(number "2"
						(effects
							(font
								(size 1.27 1.27)
							)
						)
					)
				)
			)
		)
	(symbol "antmicroFixedInductors:L_3u3_6.6A_XEL4030"
			(pin_numbers
				(hide yes)
			)
			(pin_names
				(hide yes)
			)
			(exclude_from_sim no)
			(in_bom yes)
			(on_board yes)
			(property "Reference" "L"
				(at 13.97 0 0)
				(effects
					(font
						(size 1.27 1.27)
						(thickness 0.15)
					)
					(justify left bottom)
				)
			)
			(property "Value" "L_3u3_6.6A_XEL4030"
				(at 13.97 -2.54 0)
				(effects
					(font
						(size 1.27 1.27)
						(thickness 0.15)
					)
					(justify left bottom)
					(hide yes)
				)
			)
			(property "Footprint" "antmicro-footprints:L_Coilcraft-XEL4030"
				(at 13.97 -7.62 0)
				(effects
					(font
						(size 1.27 1.27)
						(thickness 0.15)
					)
					(justify left bottom)
					(hide yes)
				)
			)
			(property "Datasheet" "https://www.coilcraft.com/getmedia/8245f050-f190-4295-8c41-7c03d662ee3d/xel4030.pdf"
				(at 13.97 -10.16 0)
				(effects
					(font
						(size 1.27 1.27)
						(thickness 0.15)
					)
					(justify left bottom)
					(hide yes)
				)
			)
			(property "Description" "Power Inductor (SMT), AEC-Q200, 3.3 µH, 6.6 A, Shielded, 5.9 A, XEL4030"
				(at 13.97 -30.48 0)
				(effects
					(font
						(size 1.27 1.27)
					)
					(justify left bottom)
					(hide yes)
				)
			)
			(property "Val" "3u3/6.6A"
				(at 13.97 -5.08 0)
				(effects
					(font
						(size 1.27 1.27)
						(thickness 0.15)
					)
					(justify left bottom)
				)
			)
			(property "Manufacturer" "Coilcraft"
				(at 13.97 -12.7 0)
				(effects
					(font
						(size 1.27 1.27)
						(thickness 0.15)
					)
					(justify left bottom)
					(hide yes)
				)
			)
			(property "MPN" "XEL4030-332MEC"
				(at 13.97 -15.24 0)
				(effects
					(font
						(size 1.27 1.27)
						(thickness 0.15)
					)
					(justify left bottom)
					(hide yes)
				)
			)
			(property "ISat" "5.9 A"
				(at 13.97 -16.51 0)
				(effects
					(font
						(size 1.27 1.27)
					)
					(justify left)
					(hide yes)
				)
			)
			(property "IMax" "6.6 A"
				(at 13.97 -20.32 0)
				(effects
					(font
						(size 1.27 1.27)
						(thickness 0.15)
					)
					(justify left bottom)
					(hide yes)
				)
			)
			(property "Size" "4.0x4.0"
				(at 13.97 -22.86 0)
				(effects
					(font
						(size 1.27 1.27)
						(thickness 0.15)
					)
					(justify left bottom)
					(hide yes)
				)
			)
			(property "Author" "Antmicro"
				(at 13.97 -25.4 0)
				(effects
					(font
						(size 1.27 1.27)
						(thickness 0.15)
					)
					(justify left bottom)
					(hide yes)
				)
			)
			(property "License" "Apache-2.0"
				(at 13.97 -27.94 0)
				(effects
					(font
						(size 1.27 1.27)
						(thickness 0.15)
					)
					(justify left bottom)
					(hide yes)
				)
			)
			(property "ki_keywords" "SMT, INDUCTOR, PASSIVE, POWER"
				(at 0 0 0)
				(effects
					(font
						(size 1.27 1.27)
					)
					(hide yes)
				)
			)
			(symbol "L_3u3_6.6A_XEL4030_0_1"
				(arc
					(start 0.508 0)
					(mid 1.016 0.5058)
					(end 1.524 0)
					(stroke
						(width 0)
						(type default)
					)
					(fill
						(type none)
					)
				)
				(arc
					(start 1.524 0)
					(mid 2.032 0.5058)
					(end 2.54 0)
					(stroke
						(width 0)
						(type default)
					)
					(fill
						(type none)
					)
				)
				(arc
					(start 2.54 0)
					(mid 3.048 0.5058)
					(end 3.556 0)
					(stroke
						(width 0)
						(type default)
					)
					(fill
						(type none)
					)
				)
				(arc
					(start 3.556 0)
					(mid 4.064 0.5058)
					(end 4.572 0)
					(stroke
						(width 0)
						(type default)
					)
					(fill
						(type none)
					)
				)
			)
			(symbol "L_3u3_6.6A_XEL4030_1_1"
				(pin passive line
					(at 0 0 0)
					(length 0.508)
					(name "~"
						(effects
							(font
								(size 1.27 1.27)
							)
						)
					)
					(number "1"
						(effects
							(font
								(size 1.27 1.27)
							)
						)
					)
				)
				(pin passive line
					(at 5.08 0 180)
					(length 0.508)
					(name "~"
						(effects
							(font
								(size 1.27 1.27)
							)
						)
					)
					(number "2"
						(effects
							(font
								(size 1.27 1.27)
							)
						)
					)
				)
			)
		)
	(symbol "antmicroFixedInductors:L_6n2_0.7A_0402"
			(pin_numbers
				(hide yes)
			)
			(pin_names
				(hide yes)
			)
			(exclude_from_sim no)
			(in_bom yes)
			(on_board yes)
			(property "Reference" "L"
				(at 13.97 0 0)
				(effects
					(font
						(size 1.27 1.27)
						(thickness 0.15)
					)
					(justify left bottom)
				)
			)
			(property "Value" "L_6n2_0.7A_0402"
				(at 13.97 -2.54 0)
				(effects
					(font
						(size 1.27 1.27)
						(thickness 0.15)
					)
					(justify left bottom)
					(hide yes)
				)
			)
			(property "Footprint" "antmicro-footprints:L_0402_1005Metric"
				(at 13.97 -7.62 0)
				(effects
					(font
						(size 1.27 1.27)
						(thickness 0.15)
					)
					(justify left bottom)
					(hide yes)
				)
			)
			(property "Datasheet" "https://www.mouser.com/datasheet/2/281/1/JELF243A_0050-1380872.pdf"
				(at 13.97 -10.16 0)
				(effects
					(font
						(size 1.27 1.27)
						(thickness 0.15)
					)
					(justify left bottom)
					(hide yes)
				)
			)
			(property "Description" "Wirewound Inductor, 6.2 nH, 0.09 ohm, 8 GHz, 700 mA, 0402 [1005 Metric], LQW"
				(at 13.97 -30.48 0)
				(effects
					(font
						(size 1.27 1.27)
					)
					(justify left bottom)
					(hide yes)
				)
			)
			(property "Val" "6n2/0.7A"
				(at 13.97 -5.08 0)
				(effects
					(font
						(size 1.27 1.27)
						(thickness 0.15)
					)
					(justify left bottom)
				)
			)
			(property "Manufacturer" "Murata"
				(at 13.97 -12.7 0)
				(effects
					(font
						(size 1.27 1.27)
						(thickness 0.15)
					)
					(justify left bottom)
					(hide yes)
				)
			)
			(property "MPN" "LQW15AN6N2C00D"
				(at 13.97 -15.24 0)
				(effects
					(font
						(size 1.27 1.27)
						(thickness 0.15)
					)
					(justify left bottom)
					(hide yes)
				)
			)
			(property "ISat" ""
				(at 13.97 -16.51 0)
				(effects
					(font
						(size 1.27 1.27)
					)
					(justify left)
					(hide yes)
				)
			)
			(property "IMax" "0.7 A"
				(at 13.97 -20.32 0)
				(effects
					(font
						(size 1.27 1.27)
						(thickness 0.15)
					)
					(justify left bottom)
					(hide yes)
				)
			)
			(property "Size" "1.0x0.5"
				(at 13.97 -22.86 0)
				(effects
					(font
						(size 1.27 1.27)
						(thickness 0.15)
					)
					(justify left bottom)
					(hide yes)
				)
			)
			(property "Author" "Antmicro"
				(at 13.97 -25.4 0)
				(effects
					(font
						(size 1.27 1.27)
						(thickness 0.15)
					)
					(justify left bottom)
					(hide yes)
				)
			)
			(property "License" "Apache-2.0"
				(at 13.97 -27.94 0)
				(effects
					(font
						(size 1.27 1.27)
						(thickness 0.15)
					)
					(justify left bottom)
					(hide yes)
				)
			)
			(property "ki_keywords" "SMT, INDUCTOR, PASSIVE"
				(at 0 0 0)
				(effects
					(font
						(size 1.27 1.27)
					)
					(hide yes)
				)
			)
			(symbol "L_6n2_0.7A_0402_0_1"
				(arc
					(start 0.508 0)
					(mid 1.016 0.5058)
					(end 1.524 0)
					(stroke
						(width 0)
						(type default)
					)
					(fill
						(type none)
					)
				)
				(arc
					(start 1.524 0)
					(mid 2.032 0.5058)
					(end 2.54 0)
					(stroke
						(width 0)
						(type default)
					)
					(fill
						(type none)
					)
				)
				(arc
					(start 2.54 0)
					(mid 3.048 0.5058)
					(end 3.556 0)
					(stroke
						(width 0)
						(type default)
					)
					(fill
						(type none)
					)
				)
				(arc
					(start 3.556 0)
					(mid 4.064 0.5058)
					(end 4.572 0)
					(stroke
						(width 0)
						(type default)
					)
					(fill
						(type none)
					)
				)
			)
			(symbol "L_6n2_0.7A_0402_1_1"
				(pin passive line
					(at 0 0 0)
					(length 0.508)
					(name "~"
						(effects
							(font
								(size 1.27 1.27)
							)
						)
					)
					(number "1"
						(effects
							(font
								(size 1.27 1.27)
							)
						)
					)
				)
				(pin passive line
					(at 5.08 0 180)
					(length 0.508)
					(name "~"
						(effects
							(font
								(size 1.27 1.27)
							)
						)
					)
					(number "2"
						(effects
							(font
								(size 1.27 1.27)
							)
						)
					)
				)
			)
		)
	(symbol "antmicroFuses:F_1.25A_0603"
			(pin_numbers
				(hide yes)
			)
			(pin_names
				(hide yes)
			)
			(exclude_from_sim no)
			(in_bom yes)
			(on_board yes)
			(property "Reference" "F"
				(at 24.13 -2.54 0)
				(effects
					(font
						(size 1.27 1.27)
						(thickness 0.15)
					)
					(justify left bottom)
				)
			)
			(property "Value" "F_1.25A_0603"
				(at 24.13 -5.08 0)
				(effects
					(font
						(size 1.27 1.27)
						(thickness 0.15)
					)
					(justify left bottom)
					(hide yes)
				)
			)
			(property "Footprint" "antmicro-footprints:F_0603_1608Metric"
				(at 24.13 -7.62 0)
				(effects
					(font
						(size 1.27 1.27)
						(thickness 0.15)
					)
					(justify left bottom)
					(hide yes)
				)
			)
			(property "Datasheet" "https://www.littelfuse.com/~/media/electronics/datasheets/fuses/littelfuse_fuse_467_datasheet.pdf.pdf"
				(at 24.13 -10.16 0)
				(effects
					(font
						(size 1.27 1.27)
						(thickness 0.15)
					)
					(justify left bottom)
					(hide yes)
				)
			)
			(property "Description" "Fuse, Surface Mount, 1.25 A, Very Fast Acting, 32 V, 32 V, 0603 (1608 Metric), 467"
				(at 24.13 -22.86 0)
				(effects
					(font
						(size 1.27 1.27)
					)
					(justify left bottom)
					(hide yes)
				)
			)
			(property "MPN" "04671.25NR"
				(at 24.13 -12.7 0)
				(effects
					(font
						(size 1.27 1.27)
						(thickness 0.15)
					)
					(justify left bottom)
				)
			)
			(property "Manufacturer" "Littelfuse"
				(at 24.13 -15.24 0)
				(effects
					(font
						(size 1.27 1.27)
						(thickness 0.15)
					)
					(justify left bottom)
					(hide yes)
				)
			)
			(property "Author" "Antmicro"
				(at 24.13 -17.78 0)
				(effects
					(font
						(size 1.27 1.27)
						(thickness 0.15)
					)
					(justify left bottom)
					(hide yes)
				)
			)
			(property "License" "Apache-2.0"
				(at 24.13 -20.32 0)
				(effects
					(font
						(size 1.27 1.27)
						(thickness 0.15)
					)
					(justify left bottom)
					(hide yes)
				)
			)
			(property "ki_keywords" "0603, SMT, FUSE, PASSIVE"
				(at 0 0 0)
				(effects
					(font
						(size 1.27 1.27)
					)
					(hide yes)
				)
			)
			(symbol "F_1.25A_0603_0_1"
				(rectangle
					(start 1.27 0.508)
					(end 3.81 -0.508)
					(stroke
						(width 0)
						(type default)
					)
					(fill
						(type none)
					)
				)
				(polyline
					(pts
						(xy 1.27 0) (xy 3.81 0)
					)
					(stroke
						(width 0)
						(type default)
					)
					(fill
						(type none)
					)
				)
			)
			(symbol "F_1.25A_0603_1_1"
				(pin passive line
					(at 0 0 0)
					(length 1.27)
					(name "~"
						(effects
							(font
								(size 1.27 1.27)
							)
						)
					)
					(number "1"
						(effects
							(font
								(size 1.27 1.27)
							)
						)
					)
				)
				(pin passive line
					(at 5.08 0 180)
					(length 1.27)
					(name "~"
						(effects
							(font
								(size 1.27 1.27)
							)
						)
					)
					(number "2"
						(effects
							(font
								(size 1.27 1.27)
							)
						)
					)
				)
			)
		)
	(symbol "antmicroGenericPinHeaders:PinHeader_1x6_P2.54mm_SMD_Horizontal"
			(exclude_from_sim no)
			(in_bom yes)
			(on_board yes)
			(property "Reference" "J"
				(at 19.05 -3.81 0)
				(effects
					(font
						(size 1.27 1.27)
						(thickness 0.15)
					)
					(justify left bottom)
				)
			)
			(property "Value" "PinHeader_1x6_P2.54mm_SMD_Horizontal"
				(at 19.05 -8.89 0)
				(effects
					(font
						(size 1.27 1.27)
						(thickness 0.15)
					)
					(justify left bottom)
					(hide yes)
				)
			)
			(property "Footprint" "antmicro-footprints:PinHeader_1x6_P2.54mm_SMD_Horizontal"
				(at 19.05 -11.43 0)
				(effects
					(font
						(size 1.27 1.27)
						(thickness 0.15)
					)
					(justify left bottom)
					(hide yes)
				)
			)
			(property "Datasheet" "https://www.mouser.com/datasheet/2/527/tsm-2854655.pdf"
				(at 19.05 -13.97 0)
				(effects
					(font
						(size 1.27 1.27)
						(thickness 0.15)
					)
					(justify left bottom)
					(hide yes)
				)
			)
			(property "Description" "Connector Header Surface Mount, Right Angle 6 position 0.100\" (2.54mm)"
				(at 19.05 -24.13 0)
				(effects
					(font
						(size 1.27 1.27)
					)
					(justify left bottom)
					(hide yes)
				)
			)
			(property "Manufacturer" "Samtec"
				(at 19.05 -16.51 0)
				(effects
					(font
						(size 1.27 1.27)
						(thickness 0.15)
					)
					(justify left bottom)
					(hide yes)
				)
			)
			(property "MPN" "TSM-106-01-T-SH"
				(at 19.05 -6.35 0)
				(effects
					(font
						(size 1.27 1.27)
						(thickness 0.15)
					)
					(justify left bottom)
				)
			)
			(property "Author" "Antmicro"
				(at 19.05 -19.05 0)
				(effects
					(font
						(size 1.27 1.27)
						(thickness 0.15)
					)
					(justify left bottom)
					(hide yes)
				)
			)
			(property "License" "Apache-2.0"
				(at 19.05 -21.59 0)
				(effects
					(font
						(size 1.27 1.27)
						(thickness 0.15)
					)
					(justify left bottom)
					(hide yes)
				)
			)
			(property "ki_keywords" "PINSTRIP, HEADER "
				(at 0 0 0)
				(effects
					(font
						(size 1.27 1.27)
					)
					(hide yes)
				)
			)
			(symbol "PinHeader_1x6_P2.54mm_SMD_Horizontal_1_1"
				(rectangle
					(start 2.54 1.27)
					(end 5.08 -13.97)
					(stroke
						(width 0.254)
						(type default)
					)
					(fill
						(type background)
					)
				)
				(rectangle
					(start 4.191 -0.254)
					(end 3.683 0.254)
					(stroke
						(width 0.254)
						(type default)
					)
					(fill
						(type background)
					)
				)
				(rectangle
					(start 4.191 -2.794)
					(end 3.683 -2.286)
					(stroke
						(width 0.254)
						(type default)
					)
					(fill
						(type background)
					)
				)
				(rectangle
					(start 4.191 -5.334)
					(end 3.683 -4.826)
					(stroke
						(width 0.254)
						(type default)
					)
					(fill
						(type background)
					)
				)
				(rectangle
					(start 4.191 -7.874)
					(end 3.683 -7.366)
					(stroke
						(width 0.254)
						(type default)
					)
					(fill
						(type background)
					)
				)
				(rectangle
					(start 4.191 -10.414)
					(end 3.683 -9.906)
					(stroke
						(width 0.254)
						(type default)
					)
					(fill
						(type background)
					)
				)
				(rectangle
					(start 4.191 -12.954)
					(end 3.683 -12.446)
					(stroke
						(width 0.254)
						(type default)
					)
					(fill
						(type background)
					)
				)
				(pin passive line
					(at 0 0 0)
					(length 2.54)
					(name "~"
						(effects
							(font
								(size 1.27 1.27)
							)
						)
					)
					(number "1"
						(effects
							(font
								(size 1.27 1.27)
							)
						)
					)
				)
				(pin passive line
					(at 0 -2.54 0)
					(length 2.54)
					(name "~"
						(effects
							(font
								(size 1.27 1.27)
							)
						)
					)
					(number "2"
						(effects
							(font
								(size 1.27 1.27)
							)
						)
					)
				)
				(pin passive line
					(at 0 -5.08 0)
					(length 2.54)
					(name "~"
						(effects
							(font
								(size 1.27 1.27)
							)
						)
					)
					(number "3"
						(effects
							(font
								(size 1.27 1.27)
							)
						)
					)
				)
				(pin passive line
					(at 0 -7.62 0)
					(length 2.54)
					(name "~"
						(effects
							(font
								(size 1.27 1.27)
							)
						)
					)
					(number "4"
						(effects
							(font
								(size 1.27 1.27)
							)
						)
					)
				)
				(pin passive line
					(at 0 -10.16 0)
					(length 2.54)
					(name "~"
						(effects
							(font
								(size 1.27 1.27)
							)
						)
					)
					(number "5"
						(effects
							(font
								(size 1.27 1.27)
							)
						)
					)
				)
				(pin passive line
					(at 0 -12.7 0)
					(length 2.54)
					(name "~"
						(effects
							(font
								(size 1.27 1.27)
							)
						)
					)
					(number "6"
						(effects
							(font
								(size 1.27 1.27)
							)
						)
					)
				)
			)
		)
	(symbol "antmicroGenericPinHeaders:PinHeader_2x5_P1.27mm_SMD"
			(exclude_from_sim no)
			(in_bom yes)
			(on_board yes)
			(property "Reference" "J"
				(at 25.4 -5.08 0)
				(effects
					(font
						(size 1.27 1.27)
						(thickness 0.15)
					)
					(justify left bottom)
				)
			)
			(property "Value" "PinHeader_2x5_P1.27mm_SMD"
				(at 25.4 -7.62 0)
				(effects
					(font
						(size 1.27 1.27)
						(thickness 0.15)
					)
					(justify left bottom)
					(hide yes)
				)
			)
			(property "Footprint" "antmicro-footprints:PinHeader_2x5_P1.27mm_SMD"
				(at 25.4 -10.16 0)
				(effects
					(font
						(size 1.27 1.27)
						(thickness 0.15)
					)
					(justify left bottom)
					(hide yes)
				)
			)
			(property "Datasheet" "https://eu.mouser.com/datasheet/2/527/ftsh_th-2854322.pdf"
				(at 25.4 -12.7 0)
				(effects
					(font
						(size 1.27 1.27)
						(thickness 0.15)
					)
					(justify left bottom)
					(hide yes)
				)
			)
			(property "Description" "Pin Header, Board-to-Board, Wire-to-Board, 1.27 mm, 2 Rows, 10 Contacts, Surface Mount, FTSH"
				(at 25.4 -25.4 0)
				(effects
					(font
						(size 1.27 1.27)
					)
					(justify left bottom)
					(hide yes)
				)
			)
			(property "MPN" "FTSH-105-01-F-DV"
				(at 25.4 -15.24 0)
				(effects
					(font
						(size 1.27 1.27)
						(thickness 0.15)
					)
					(justify left bottom)
				)
			)
			(property "Manufacturer" "Samtec"
				(at 25.4 -17.78 0)
				(effects
					(font
						(size 1.27 1.27)
						(thickness 0.15)
					)
					(justify left bottom)
					(hide yes)
				)
			)
			(property "Author" "Antmicro"
				(at 25.4 -20.32 0)
				(effects
					(font
						(size 1.27 1.27)
						(thickness 0.15)
					)
					(justify left bottom)
					(hide yes)
				)
			)
			(property "License" "Apache-2.0"
				(at 25.4 -22.86 0)
				(effects
					(font
						(size 1.27 1.27)
						(thickness 0.15)
					)
					(justify left bottom)
					(hide yes)
				)
			)
			(property "ki_keywords" "PINSTRIP, HEADER "
				(at 0 0 0)
				(effects
					(font
						(size 1.27 1.27)
					)
					(hide yes)
				)
			)
			(symbol "PinHeader_2x5_P1.27mm_SMD_1_1"
				(rectangle
					(start 2.54 1.27)
					(end 7.62 -11.43)
					(stroke
						(width 0.254)
						(type default)
					)
					(fill
						(type background)
					)
				)
				(rectangle
					(start 3.556 0.254)
					(end 4.064 -0.254)
					(stroke
						(width 0.254)
						(type default)
					)
					(fill
						(type outline)
					)
				)
				(rectangle
					(start 3.556 -2.286)
					(end 4.064 -2.794)
					(stroke
						(width 0.254)
						(type default)
					)
					(fill
						(type outline)
					)
				)
				(rectangle
					(start 3.556 -4.826)
					(end 4.064 -5.334)
					(stroke
						(width 0.254)
						(type default)
					)
					(fill
						(type outline)
					)
				)
				(rectangle
					(start 3.556 -7.366)
					(end 4.064 -7.874)
					(stroke
						(width 0.254)
						(type default)
					)
					(fill
						(type outline)
					)
				)
				(rectangle
					(start 3.556 -9.906)
					(end 4.064 -10.414)
					(stroke
						(width 0.254)
						(type default)
					)
					(fill
						(type outline)
					)
				)
				(rectangle
					(start 6.096 0.254)
					(end 6.604 -0.254)
					(stroke
						(width 0.254)
						(type default)
					)
					(fill
						(type outline)
					)
				)
				(rectangle
					(start 6.096 -2.286)
					(end 6.604 -2.794)
					(stroke
						(width 0.254)
						(type default)
					)
					(fill
						(type outline)
					)
				)
				(rectangle
					(start 6.096 -4.826)
					(end 6.604 -5.334)
					(stroke
						(width 0.254)
						(type default)
					)
					(fill
						(type outline)
					)
				)
				(rectangle
					(start 6.096 -7.366)
					(end 6.604 -7.874)
					(stroke
						(width 0.254)
						(type default)
					)
					(fill
						(type outline)
					)
				)
				(rectangle
					(start 6.096 -9.906)
					(end 6.604 -10.414)
					(stroke
						(width 0.254)
						(type default)
					)
					(fill
						(type outline)
					)
				)
				(pin passive line
					(at 0 0 0)
					(length 2.54)
					(name "~"
						(effects
							(font
								(size 1.27 1.27)
							)
						)
					)
					(number "1"
						(effects
							(font
								(size 1.27 1.27)
							)
						)
					)
				)
				(pin passive line
					(at 0 -2.54 0)
					(length 2.54)
					(name "~"
						(effects
							(font
								(size 1.27 1.27)
							)
						)
					)
					(number "3"
						(effects
							(font
								(size 1.27 1.27)
							)
						)
					)
				)
				(pin passive line
					(at 0 -5.08 0)
					(length 2.54)
					(name "~"
						(effects
							(font
								(size 1.27 1.27)
							)
						)
					)
					(number "5"
						(effects
							(font
								(size 1.27 1.27)
							)
						)
					)
				)
				(pin passive line
					(at 0 -7.62 0)
					(length 2.54)
					(name "~"
						(effects
							(font
								(size 1.27 1.27)
							)
						)
					)
					(number "7"
						(effects
							(font
								(size 1.27 1.27)
							)
						)
					)
				)
				(pin passive line
					(at 0 -10.16 0)
					(length 2.54)
					(name "~"
						(effects
							(font
								(size 1.27 1.27)
							)
						)
					)
					(number "9"
						(effects
							(font
								(size 1.27 1.27)
							)
						)
					)
				)
				(pin passive line
					(at 10.16 0 180)
					(length 2.54)
					(name "~"
						(effects
							(font
								(size 1.27 1.27)
							)
						)
					)
					(number "2"
						(effects
							(font
								(size 1.27 1.27)
							)
						)
					)
				)
				(pin passive line
					(at 10.16 -2.54 180)
					(length 2.54)
					(name "~"
						(effects
							(font
								(size 1.27 1.27)
							)
						)
					)
					(number "4"
						(effects
							(font
								(size 1.27 1.27)
							)
						)
					)
				)
				(pin passive line
					(at 10.16 -5.08 180)
					(length 2.54)
					(name "~"
						(effects
							(font
								(size 1.27 1.27)
							)
						)
					)
					(number "6"
						(effects
							(font
								(size 1.27 1.27)
							)
						)
					)
				)
				(pin passive line
					(at 10.16 -7.62 180)
					(length 2.54)
					(name "~"
						(effects
							(font
								(size 1.27 1.27)
							)
						)
					)
					(number "8"
						(effects
							(font
								(size 1.27 1.27)
							)
						)
					)
				)
				(pin passive line
					(at 10.16 -10.16 180)
					(length 2.54)
					(name "~"
						(effects
							(font
								(size 1.27 1.27)
							)
						)
					)
					(number "10"
						(effects
							(font
								(size 1.27 1.27)
							)
						)
					)
				)
			)
		)
	(symbol "antmicroGenericPinHeaders:PinHeader_2x5_P1.27mm_SMD_Shrouded"
			(pin_names
				(hide yes)
			)
			(exclude_from_sim no)
			(in_bom yes)
			(on_board yes)
			(property "Reference" "J"
				(at 25.4 -5.08 0)
				(effects
					(font
						(size 1.27 1.27)
						(thickness 0.15)
					)
					(justify left bottom)
				)
			)
			(property "Value" "PinHeader_2x5_P1.27mm_SMD_Shrouded"
				(at 25.4 -7.62 0)
				(effects
					(font
						(size 1.27 1.27)
						(thickness 0.15)
					)
					(justify left bottom)
					(hide yes)
				)
			)
			(property "Footprint" "antmicro-footprints:PinHeader_2x5_P1.27mm_SMD_Shrouded"
				(at 25.4 -10.16 0)
				(effects
					(font
						(size 1.27 1.27)
						(thickness 0.15)
					)
					(justify left bottom)
					(hide yes)
				)
			)
			(property "Datasheet" "https://eu.mouser.com/datasheet/2/527/shf-1370134.pdf"
				(at 25.4 -12.7 0)
				(effects
					(font
						(size 1.27 1.27)
						(thickness 0.15)
					)
					(justify left bottom)
					(hide yes)
				)
			)
			(property "Description" "Headers & Wire Housings Shrouded Terminal Strip, 0.050\" pitch"
				(at 25.4 -25.4 0)
				(effects
					(font
						(size 1.27 1.27)
					)
					(justify left bottom)
					(hide yes)
				)
			)
			(property "MPN" "SHF-105-01-L-D-SM"
				(at 25.4 -15.24 0)
				(effects
					(font
						(size 1.27 1.27)
						(thickness 0.15)
					)
					(justify left bottom)
				)
			)
			(property "Manufacturer" "Samtec"
				(at 25.4 -17.78 0)
				(effects
					(font
						(size 1.27 1.27)
						(thickness 0.15)
					)
					(justify left bottom)
					(hide yes)
				)
			)
			(property "Author" "Antmicro"
				(at 25.4 -20.32 0)
				(effects
					(font
						(size 1.27 1.27)
						(thickness 0.15)
					)
					(justify left bottom)
					(hide yes)
				)
			)
			(property "License" "Apache-2.0"
				(at 25.4 -22.86 0)
				(effects
					(font
						(size 1.27 1.27)
						(thickness 0.15)
					)
					(justify left bottom)
					(hide yes)
				)
			)
			(property "ki_keywords" "SMT, HEADER, CONNECTOR"
				(at 0 0 0)
				(effects
					(font
						(size 1.27 1.27)
					)
					(hide yes)
				)
			)
			(symbol "PinHeader_2x5_P1.27mm_SMD_Shrouded_1_1"
				(rectangle
					(start 2.54 1.27)
					(end 7.62 -11.43)
					(stroke
						(width 0.254)
						(type default)
					)
					(fill
						(type background)
					)
				)
				(rectangle
					(start 3.556 0.254)
					(end 4.064 -0.254)
					(stroke
						(width 0.254)
						(type default)
					)
					(fill
						(type outline)
					)
				)
				(rectangle
					(start 3.556 -2.286)
					(end 4.064 -2.794)
					(stroke
						(width 0.254)
						(type default)
					)
					(fill
						(type outline)
					)
				)
				(rectangle
					(start 3.556 -4.826)
					(end 4.064 -5.334)
					(stroke
						(width 0.254)
						(type default)
					)
					(fill
						(type outline)
					)
				)
				(rectangle
					(start 3.556 -7.366)
					(end 4.064 -7.874)
					(stroke
						(width 0.254)
						(type default)
					)
					(fill
						(type outline)
					)
				)
				(rectangle
					(start 3.556 -9.906)
					(end 4.064 -10.414)
					(stroke
						(width 0.254)
						(type default)
					)
					(fill
						(type outline)
					)
				)
				(rectangle
					(start 6.096 0.254)
					(end 6.604 -0.254)
					(stroke
						(width 0.254)
						(type default)
					)
					(fill
						(type outline)
					)
				)
				(rectangle
					(start 6.096 -2.286)
					(end 6.604 -2.794)
					(stroke
						(width 0.254)
						(type default)
					)
					(fill
						(type outline)
					)
				)
				(rectangle
					(start 6.096 -4.826)
					(end 6.604 -5.334)
					(stroke
						(width 0.254)
						(type default)
					)
					(fill
						(type outline)
					)
				)
				(rectangle
					(start 6.096 -7.366)
					(end 6.604 -7.874)
					(stroke
						(width 0.254)
						(type default)
					)
					(fill
						(type outline)
					)
				)
				(rectangle
					(start 6.096 -9.906)
					(end 6.604 -10.414)
					(stroke
						(width 0.254)
						(type default)
					)
					(fill
						(type outline)
					)
				)
				(pin passive line
					(at 0 0 0)
					(length 2.54)
					(name "1"
						(effects
							(font
								(size 1.27 1.27)
							)
						)
					)
					(number "1"
						(effects
							(font
								(size 1.27 1.27)
							)
						)
					)
				)
				(pin passive line
					(at 0 -2.54 0)
					(length 2.54)
					(name "3"
						(effects
							(font
								(size 1.27 1.27)
							)
						)
					)
					(number "3"
						(effects
							(font
								(size 1.27 1.27)
							)
						)
					)
				)
				(pin passive line
					(at 0 -5.08 0)
					(length 2.54)
					(name "5"
						(effects
							(font
								(size 1.27 1.27)
							)
						)
					)
					(number "5"
						(effects
							(font
								(size 1.27 1.27)
							)
						)
					)
				)
				(pin passive line
					(at 0 -7.62 0)
					(length 2.54)
					(name "7"
						(effects
							(font
								(size 1.27 1.27)
							)
						)
					)
					(number "7"
						(effects
							(font
								(size 1.27 1.27)
							)
						)
					)
				)
				(pin passive line
					(at 0 -10.16 0)
					(length 2.54)
					(name "9"
						(effects
							(font
								(size 1.27 1.27)
							)
						)
					)
					(number "9"
						(effects
							(font
								(size 1.27 1.27)
							)
						)
					)
				)
				(pin passive line
					(at 10.16 0 180)
					(length 2.54)
					(name "2"
						(effects
							(font
								(size 1.27 1.27)
							)
						)
					)
					(number "2"
						(effects
							(font
								(size 1.27 1.27)
							)
						)
					)
				)
				(pin passive line
					(at 10.16 -2.54 180)
					(length 2.54)
					(name "4"
						(effects
							(font
								(size 1.27 1.27)
							)
						)
					)
					(number "4"
						(effects
							(font
								(size 1.27 1.27)
							)
						)
					)
				)
				(pin passive line
					(at 10.16 -5.08 180)
					(length 2.54)
					(name "6"
						(effects
							(font
								(size 1.27 1.27)
							)
						)
					)
					(number "6"
						(effects
							(font
								(size 1.27 1.27)
							)
						)
					)
				)
				(pin passive line
					(at 10.16 -7.62 180)
					(length 2.54)
					(name "8"
						(effects
							(font
								(size 1.27 1.27)
							)
						)
					)
					(number "8"
						(effects
							(font
								(size 1.27 1.27)
							)
						)
					)
				)
				(pin passive line
					(at 10.16 -10.16 180)
					(length 2.54)
					(name "10"
						(effects
							(font
								(size 1.27 1.27)
							)
						)
					)
					(number "10"
						(effects
							(font
								(size 1.27 1.27)
							)
						)
					)
				)
			)
		)
	(symbol "antmicroInterfaceControllers:FT230X_QFN"
			(exclude_from_sim no)
			(in_bom yes)
			(on_board yes)
			(property "Reference" "U"
				(at 39.37 -7.62 0)
				(effects
					(font
						(size 1.27 1.27)
						(thickness 0.15)
					)
					(justify left bottom)
				)
			)
			(property "Value" "FT230X_QFN"
				(at 39.37 -10.16 0)
				(effects
					(font
						(size 1.27 1.27)
						(thickness 0.15)
					)
					(justify left bottom)
					(hide yes)
				)
			)
			(property "Footprint" "antmicro-footprints:QFN-16-1EP_4x4mm_P0.65mm"
				(at 39.37 -12.7 0)
				(effects
					(font
						(size 1.27 1.27)
						(thickness 0.15)
					)
					(justify left bottom)
					(hide yes)
				)
			)
			(property "Datasheet" "https://ftdichip.com/wp-content/uploads/2021/10/DS_FT230X.pdf"
				(at 39.37 -15.24 0)
				(effects
					(font
						(size 1.27 1.27)
						(thickness 0.15)
					)
					(justify left bottom)
					(hide yes)
				)
			)
			(property "Description" "USB Interface, USB-UART Converter, USB 2.0, 2.97 V, 5.5 V, QFN, 16 Pins"
				(at 39.37 -27.94 0)
				(effects
					(font
						(size 1.27 1.27)
					)
					(justify left bottom)
					(hide yes)
				)
			)
			(property "MPN" "FT230XQ-R"
				(at 39.37 -20.32 0)
				(effects
					(font
						(size 1.27 1.27)
						(thickness 0.15)
					)
					(justify left bottom)
				)
			)
			(property "Manufacturer" "FTDI Chip"
				(at 39.37 -17.78 0)
				(effects
					(font
						(size 1.27 1.27)
						(thickness 0.15)
					)
					(justify left bottom)
					(hide yes)
				)
			)
			(property "Author" "Antmicro"
				(at 39.37 -22.86 0)
				(effects
					(font
						(size 1.27 1.27)
						(thickness 0.15)
					)
					(justify left bottom)
					(hide yes)
				)
			)
			(property "License" "Apache-2.0"
				(at 39.37 -25.4 0)
				(effects
					(font
						(size 1.27 1.27)
						(thickness 0.15)
					)
					(justify left bottom)
					(hide yes)
				)
			)
			(property "ki_keywords" "SMT, INTERFACE, IC, CONTROLLER, USB, UART"
				(at 0 0 0)
				(effects
					(font
						(size 1.27 1.27)
					)
					(hide yes)
				)
			)
			(symbol "FT230X_QFN_1_1"
				(rectangle
					(start 2.54 2.54)
					(end 20.32 -22.86)
					(stroke
						(width 0.254)
						(type default)
					)
					(fill
						(type background)
					)
				)
				(pin power_in line
					(at 0 0 0)
					(length 2.54)
					(name "V_{CC}"
						(effects
							(font
								(size 1.27 1.27)
							)
						)
					)
					(number "10"
						(effects
							(font
								(size 1.27 1.27)
							)
						)
					)
				)
				(pin power_in line
					(at 0 -2.54 0)
					(length 2.54)
					(name "V_{CCIO}"
						(effects
							(font
								(size 1.27 1.27)
							)
						)
					)
					(number "1"
						(effects
							(font
								(size 1.27 1.27)
							)
						)
					)
				)
				(pin passive line
					(at 0 -5.08 0)
					(length 2.54)
					(name "3V3_{OUT}"
						(effects
							(font
								(size 1.27 1.27)
							)
						)
					)
					(number "8"
						(effects
							(font
								(size 1.27 1.27)
							)
						)
					)
				)
				(pin input line
					(at 0 -8.89 0)
					(length 2.54)
					(name "D+"
						(effects
							(font
								(size 1.27 1.27)
							)
						)
					)
					(number "6"
						(effects
							(font
								(size 1.27 1.27)
							)
						)
					)
				)
				(pin input line
					(at 0 -11.43 0)
					(length 2.54)
					(name "D-"
						(effects
							(font
								(size 1.27 1.27)
							)
						)
					)
					(number "7"
						(effects
							(font
								(size 1.27 1.27)
							)
						)
					)
				)
				(pin input line
					(at 0 -15.24 0)
					(length 2.54)
					(name "~{RESET}"
						(effects
							(font
								(size 1.27 1.27)
							)
						)
					)
					(number "9"
						(effects
							(font
								(size 1.27 1.27)
							)
						)
					)
				)
				(pin power_in line
					(at 0 -20.32 0)
					(length 2.54)
					(name "GND"
						(effects
							(font
								(size 1.27 1.27)
							)
						)
					)
					(number "13"
						(effects
							(font
								(size 1.27 1.27)
							)
						)
					)
				)
				(pin passive line
					(at 0 -20.32 0)
					(length 2.54)
					(hide yes)
					(name "GND"
						(effects
							(font
								(size 1.27 1.27)
							)
						)
					)
					(number "17"
						(effects
							(font
								(size 1.27 1.27)
							)
						)
					)
				)
				(pin passive line
					(at 0 -20.32 0)
					(length 2.54)
					(hide yes)
					(name "GND"
						(effects
							(font
								(size 1.27 1.27)
							)
						)
					)
					(number "3"
						(effects
							(font
								(size 1.27 1.27)
							)
						)
					)
				)
				(pin output line
					(at 22.86 0 180)
					(length 2.54)
					(name "TXD"
						(effects
							(font
								(size 1.27 1.27)
							)
						)
					)
					(number "15"
						(effects
							(font
								(size 1.27 1.27)
							)
						)
					)
				)
				(pin input line
					(at 22.86 -2.54 180)
					(length 2.54)
					(name "RXD"
						(effects
							(font
								(size 1.27 1.27)
							)
						)
					)
					(number "2"
						(effects
							(font
								(size 1.27 1.27)
							)
						)
					)
				)
				(pin output line
					(at 22.86 -5.08 180)
					(length 2.54)
					(name "~{RTS}"
						(effects
							(font
								(size 1.27 1.27)
							)
						)
					)
					(number "16"
						(effects
							(font
								(size 1.27 1.27)
							)
						)
					)
				)
				(pin input line
					(at 22.86 -7.62 180)
					(length 2.54)
					(name "~{CTS}"
						(effects
							(font
								(size 1.27 1.27)
							)
						)
					)
					(number "4"
						(effects
							(font
								(size 1.27 1.27)
							)
						)
					)
				)
				(pin bidirectional line
					(at 22.86 -12.7 180)
					(length 2.54)
					(name "CBUS0"
						(effects
							(font
								(size 1.27 1.27)
							)
						)
					)
					(number "12"
						(effects
							(font
								(size 1.27 1.27)
							)
						)
					)
				)
				(pin bidirectional line
					(at 22.86 -15.24 180)
					(length 2.54)
					(name "CBUS1"
						(effects
							(font
								(size 1.27 1.27)
							)
						)
					)
					(number "11"
						(effects
							(font
								(size 1.27 1.27)
							)
						)
					)
				)
				(pin bidirectional line
					(at 22.86 -17.78 180)
					(length 2.54)
					(name "CBUS2"
						(effects
							(font
								(size 1.27 1.27)
							)
						)
					)
					(number "5"
						(effects
							(font
								(size 1.27 1.27)
							)
						)
					)
				)
				(pin bidirectional line
					(at 22.86 -20.32 180)
					(length 2.54)
					(name "CBUS3"
						(effects
							(font
								(size 1.27 1.27)
							)
						)
					)
					(number "14"
						(effects
							(font
								(size 1.27 1.27)
							)
						)
					)
				)
			)
		)
	(symbol "antmicroInterfaceControllers:GS2971A"
			(exclude_from_sim no)
			(in_bom yes)
			(on_board yes)
			(property "Reference" "U"
				(at 55.88 -2.54 0)
				(effects
					(font
						(size 1.27 1.27)
						(thickness 0.15)
					)
					(justify left bottom)
				)
			)
			(property "Value" "GS2971A"
				(at 55.88 -5.08 0)
				(effects
					(font
						(size 1.27 1.27)
						(thickness 0.15)
					)
					(justify left bottom)
					(hide yes)
				)
			)
			(property "Footprint" "antmicro-footprints:BGA-100_11x11mm_Layout10x10_P1mm"
				(at 55.88 -7.62 0)
				(effects
					(font
						(size 1.27 1.27)
						(thickness 0.15)
					)
					(justify left bottom)
					(hide yes)
				)
			)
			(property "Datasheet" "https://semtech.my.salesforce.com/sfc/p/#E0000000JelG/a/44000000MD3i/kpmMkrmUWgHlbCOwdLzVohMm1SDPoVH85guEGK.KXTc"
				(at 55.88 -10.16 0)
				(effects
					(font
						(size 1.27 1.27)
						(thickness 0.15)
					)
					(justify left bottom)
					(hide yes)
				)
			)
			(property "Description" "SDI receiver"
				(at 55.88 -22.86 0)
				(effects
					(font
						(size 1.27 1.27)
					)
					(justify left bottom)
					(hide yes)
				)
			)
			(property "MPN" "GS2971A"
				(at 55.88 -12.7 0)
				(effects
					(font
						(size 1.27 1.27)
						(thickness 0.15)
					)
					(justify left bottom)
				)
			)
			(property "Manufacturer" "Semtech"
				(at 55.88 -15.24 0)
				(effects
					(font
						(size 1.27 1.27)
						(thickness 0.15)
					)
					(justify left bottom)
					(hide yes)
				)
			)
			(property "Author" "Antmicro"
				(at 55.88 -17.78 0)
				(effects
					(font
						(size 1.27 1.27)
						(thickness 0.15)
					)
					(justify left bottom)
					(hide yes)
				)
			)
			(property "License" "Apache-2.0"
				(at 55.88 -20.32 0)
				(effects
					(font
						(size 1.27 1.27)
						(thickness 0.15)
					)
					(justify left bottom)
					(hide yes)
				)
			)
			(property "ki_locked" ""
				(at 0 0 0)
				(effects
					(font
						(size 1.27 1.27)
					)
				)
			)
			(property "ki_keywords" "IC"
				(at 0 0 0)
				(effects
					(font
						(size 1.27 1.27)
					)
					(hide yes)
				)
			)
			(symbol "GS2971A_1_1"
				(rectangle
					(start 3.81 2.54)
					(end 22.86 -50.8)
					(stroke
						(width 0.254)
						(type default)
					)
					(fill
						(type background)
					)
				)
				(pin output line
					(at 0 0 0)
					(length 3.81)
					(name "PCLK"
						(effects
							(font
								(size 1.27 1.27)
							)
						)
					)
					(number "A8"
						(effects
							(font
								(size 1.27 1.27)
							)
						)
					)
				)
				(pin output line
					(at 0 -3.81 0)
					(length 3.81)
					(name "STAT0"
						(effects
							(font
								(size 1.27 1.27)
							)
						)
					)
					(number "A5"
						(effects
							(font
								(size 1.27 1.27)
							)
						)
					)
				)
				(pin output line
					(at 0 -6.35 0)
					(length 3.81)
					(name "STAT1"
						(effects
							(font
								(size 1.27 1.27)
							)
						)
					)
					(number "A6"
						(effects
							(font
								(size 1.27 1.27)
							)
						)
					)
				)
				(pin output line
					(at 0 -8.89 0)
					(length 3.81)
					(name "STAT2"
						(effects
							(font
								(size 1.27 1.27)
							)
						)
					)
					(number "B5"
						(effects
							(font
								(size 1.27 1.27)
							)
						)
					)
				)
				(pin output line
					(at 0 -11.43 0)
					(length 3.81)
					(name "STAT3"
						(effects
							(font
								(size 1.27 1.27)
							)
						)
					)
					(number "B6"
						(effects
							(font
								(size 1.27 1.27)
							)
						)
					)
				)
				(pin output line
					(at 0 -13.97 0)
					(length 3.81)
					(name "STAT4"
						(effects
							(font
								(size 1.27 1.27)
							)
						)
					)
					(number "C5"
						(effects
							(font
								(size 1.27 1.27)
							)
						)
					)
				)
				(pin output line
					(at 0 -16.51 0)
					(length 3.81)
					(name "STAT5"
						(effects
							(font
								(size 1.27 1.27)
							)
						)
					)
					(number "C6"
						(effects
							(font
								(size 1.27 1.27)
							)
						)
					)
				)
				(pin output line
					(at 0 -20.32 0)
					(length 3.81)
					(name "WCLK"
						(effects
							(font
								(size 1.27 1.27)
							)
						)
					)
					(number "H4"
						(effects
							(font
								(size 1.27 1.27)
							)
						)
					)
				)
				(pin output line
					(at 0 -22.86 0)
					(length 3.81)
					(name "ACLK"
						(effects
							(font
								(size 1.27 1.27)
							)
						)
					)
					(number "J4"
						(effects
							(font
								(size 1.27 1.27)
							)
						)
					)
				)
				(pin output line
					(at 0 -25.4 0)
					(length 3.81)
					(name "AMCLK"
						(effects
							(font
								(size 1.27 1.27)
							)
						)
					)
					(number "K4"
						(effects
							(font
								(size 1.27 1.27)
							)
						)
					)
				)
				(pin output line
					(at 0 -30.48 0)
					(length 3.81)
					(name "AOUT_{1/2}"
						(effects
							(font
								(size 1.27 1.27)
							)
						)
					)
					(number "J3"
						(effects
							(font
								(size 1.27 1.27)
							)
						)
					)
				)
				(pin output line
					(at 0 -33.02 0)
					(length 3.81)
					(name "AOUT_{3/4}"
						(effects
							(font
								(size 1.27 1.27)
							)
						)
					)
					(number "K3"
						(effects
							(font
								(size 1.27 1.27)
							)
						)
					)
				)
				(pin output line
					(at 0 -35.56 0)
					(length 3.81)
					(name "AOUT_{5/6}"
						(effects
							(font
								(size 1.27 1.27)
							)
						)
					)
					(number "J5"
						(effects
							(font
								(size 1.27 1.27)
							)
						)
					)
				)
				(pin output line
					(at 0 -38.1 0)
					(length 3.81)
					(name "AOUT_{7/8}"
						(effects
							(font
								(size 1.27 1.27)
							)
						)
					)
					(number "K5"
						(effects
							(font
								(size 1.27 1.27)
							)
						)
					)
				)
				(pin output line
					(at 0 -43.18 0)
					(length 3.81)
					(name "SDO+"
						(effects
							(font
								(size 1.27 1.27)
							)
						)
					)
					(number "J1"
						(effects
							(font
								(size 1.27 1.27)
							)
						)
					)
				)
				(pin output line
					(at 0 -45.72 0)
					(length 3.81)
					(name "SDO-"
						(effects
							(font
								(size 1.27 1.27)
							)
						)
					)
					(number "K1"
						(effects
							(font
								(size 1.27 1.27)
							)
						)
					)
				)
				(pin output line
					(at 26.67 0 180)
					(length 3.81)
					(name "DOUT0"
						(effects
							(font
								(size 1.27 1.27)
							)
						)
					)
					(number "K8"
						(effects
							(font
								(size 1.27 1.27)
							)
						)
					)
				)
				(pin output line
					(at 26.67 -2.54 180)
					(length 3.81)
					(name "DOUT01"
						(effects
							(font
								(size 1.27 1.27)
							)
						)
					)
					(number "J8"
						(effects
							(font
								(size 1.27 1.27)
							)
						)
					)
				)
				(pin output line
					(at 26.67 -5.08 180)
					(length 3.81)
					(name "DOUT02"
						(effects
							(font
								(size 1.27 1.27)
							)
						)
					)
					(number "K9"
						(effects
							(font
								(size 1.27 1.27)
							)
						)
					)
				)
				(pin output line
					(at 26.67 -7.62 180)
					(length 3.81)
					(name "DOUT03"
						(effects
							(font
								(size 1.27 1.27)
							)
						)
					)
					(number "K10"
						(effects
							(font
								(size 1.27 1.27)
							)
						)
					)
				)
				(pin output line
					(at 26.67 -10.16 180)
					(length 3.81)
					(name "DOUT04"
						(effects
							(font
								(size 1.27 1.27)
							)
						)
					)
					(number "J9"
						(effects
							(font
								(size 1.27 1.27)
							)
						)
					)
				)
				(pin output line
					(at 26.67 -12.7 180)
					(length 3.81)
					(name "DOUT05"
						(effects
							(font
								(size 1.27 1.27)
							)
						)
					)
					(number "J10"
						(effects
							(font
								(size 1.27 1.27)
							)
						)
					)
				)
				(pin output line
					(at 26.67 -15.24 180)
					(length 3.81)
					(name "DOUT06"
						(effects
							(font
								(size 1.27 1.27)
							)
						)
					)
					(number "H9"
						(effects
							(font
								(size 1.27 1.27)
							)
						)
					)
				)
				(pin output line
					(at 26.67 -17.78 180)
					(length 3.81)
					(name "DOUT07"
						(effects
							(font
								(size 1.27 1.27)
							)
						)
					)
					(number "H10"
						(effects
							(font
								(size 1.27 1.27)
							)
						)
					)
				)
				(pin output line
					(at 26.67 -20.32 180)
					(length 3.81)
					(name "DOUT08"
						(effects
							(font
								(size 1.27 1.27)
							)
						)
					)
					(number "F9"
						(effects
							(font
								(size 1.27 1.27)
							)
						)
					)
				)
				(pin output line
					(at 26.67 -22.86 180)
					(length 3.81)
					(name "DOUT09"
						(effects
							(font
								(size 1.27 1.27)
							)
						)
					)
					(number "F10"
						(effects
							(font
								(size 1.27 1.27)
							)
						)
					)
				)
				(pin output line
					(at 26.67 -25.4 180)
					(length 3.81)
					(name "DOUT10"
						(effects
							(font
								(size 1.27 1.27)
							)
						)
					)
					(number "E9"
						(effects
							(font
								(size 1.27 1.27)
							)
						)
					)
				)
				(pin output line
					(at 26.67 -27.94 180)
					(length 3.81)
					(name "DOUT11"
						(effects
							(font
								(size 1.27 1.27)
							)
						)
					)
					(number "E10"
						(effects
							(font
								(size 1.27 1.27)
							)
						)
					)
				)
				(pin output line
					(at 26.67 -30.48 180)
					(length 3.81)
					(name "DOUT12"
						(effects
							(font
								(size 1.27 1.27)
							)
						)
					)
					(number "C8"
						(effects
							(font
								(size 1.27 1.27)
							)
						)
					)
				)
				(pin output line
					(at 26.67 -33.02 180)
					(length 3.81)
					(name "DOUT13"
						(effects
							(font
								(size 1.27 1.27)
							)
						)
					)
					(number "C10"
						(effects
							(font
								(size 1.27 1.27)
							)
						)
					)
				)
				(pin output line
					(at 26.67 -35.56 180)
					(length 3.81)
					(name "DOUT14"
						(effects
							(font
								(size 1.27 1.27)
							)
						)
					)
					(number "C9"
						(effects
							(font
								(size 1.27 1.27)
							)
						)
					)
				)
				(pin output line
					(at 26.67 -38.1 180)
					(length 3.81)
					(name "DOUT15"
						(effects
							(font
								(size 1.27 1.27)
							)
						)
					)
					(number "B10"
						(effects
							(font
								(size 1.27 1.27)
							)
						)
					)
				)
				(pin output line
					(at 26.67 -40.64 180)
					(length 3.81)
					(name "DOUT16"
						(effects
							(font
								(size 1.27 1.27)
							)
						)
					)
					(number "B9"
						(effects
							(font
								(size 1.27 1.27)
							)
						)
					)
				)
				(pin output line
					(at 26.67 -43.18 180)
					(length 3.81)
					(name "DOUT17"
						(effects
							(font
								(size 1.27 1.27)
							)
						)
					)
					(number "A10"
						(effects
							(font
								(size 1.27 1.27)
							)
						)
					)
				)
				(pin output line
					(at 26.67 -45.72 180)
					(length 3.81)
					(name "DOUT18"
						(effects
							(font
								(size 1.27 1.27)
							)
						)
					)
					(number "A9"
						(effects
							(font
								(size 1.27 1.27)
							)
						)
					)
				)
				(pin output line
					(at 26.67 -48.26 180)
					(length 3.81)
					(name "DOUT19"
						(effects
							(font
								(size 1.27 1.27)
							)
						)
					)
					(number "B8"
						(effects
							(font
								(size 1.27 1.27)
							)
						)
					)
				)
			)
			(symbol "GS2971A_2_1"
				(rectangle
					(start 3.81 2.54)
					(end 27.94 -40.64)
					(stroke
						(width 0.254)
						(type default)
					)
					(fill
						(type background)
					)
				)
				(pin input line
					(at 0 0 0)
					(length 3.81)
					(name "LB_CONT"
						(effects
							(font
								(size 1.27 1.27)
							)
						)
					)
					(number "A3"
						(effects
							(font
								(size 1.27 1.27)
							)
						)
					)
				)
				(pin input line
					(at 0 -2.54 0)
					(length 3.81)
					(name "LF"
						(effects
							(font
								(size 1.27 1.27)
							)
						)
					)
					(number "A2"
						(effects
							(font
								(size 1.27 1.27)
							)
						)
					)
				)
				(pin input line
					(at 0 -5.08 0)
					(length 3.81)
					(name "VBG"
						(effects
							(font
								(size 1.27 1.27)
							)
						)
					)
					(number "A1"
						(effects
							(font
								(size 1.27 1.27)
							)
						)
					)
				)
				(pin input line
					(at 0 -10.16 0)
					(length 3.81)
					(name "XTAL1"
						(effects
							(font
								(size 1.27 1.27)
							)
						)
					)
					(number "K6"
						(effects
							(font
								(size 1.27 1.27)
							)
						)
					)
				)
				(pin input line
					(at 0 -12.7 0)
					(length 3.81)
					(name "XTAL2"
						(effects
							(font
								(size 1.27 1.27)
							)
						)
					)
					(number "J6"
						(effects
							(font
								(size 1.27 1.27)
							)
						)
					)
				)
				(pin output line
					(at 0 -15.24 0)
					(length 3.81)
					(name "XTAL_OUT"
						(effects
							(font
								(size 1.27 1.27)
							)
						)
					)
					(number "H6"
						(effects
							(font
								(size 1.27 1.27)
							)
						)
					)
				)
				(pin passive line
					(at 0 -22.86 0)
					(length 3.81)
					(name "AGC+"
						(effects
							(font
								(size 1.27 1.27)
							)
						)
					)
					(number "F1"
						(effects
							(font
								(size 1.27 1.27)
							)
						)
					)
				)
				(pin passive line
					(at 0 -25.4 0)
					(length 3.81)
					(name "AGC-"
						(effects
							(font
								(size 1.27 1.27)
							)
						)
					)
					(number "G1"
						(effects
							(font
								(size 1.27 1.27)
							)
						)
					)
				)
				(pin input line
					(at 0 -31.75 0)
					(length 3.81)
					(name "SDI+"
						(effects
							(font
								(size 1.27 1.27)
							)
						)
					)
					(number "C1"
						(effects
							(font
								(size 1.27 1.27)
							)
						)
					)
				)
				(pin input line
					(at 0 -34.29 0)
					(length 3.81)
					(name "SDI-"
						(effects
							(font
								(size 1.27 1.27)
							)
						)
					)
					(number "D1"
						(effects
							(font
								(size 1.27 1.27)
							)
						)
					)
				)
				(pin no_connect line
					(at 3.81 -17.78 0)
					(length 3.81)
					(hide yes)
					(name "RSV"
						(effects
							(font
								(size 1.27 1.27)
							)
						)
					)
					(number "B3"
						(effects
							(font
								(size 1.27 1.27)
							)
						)
					)
				)
				(pin no_connect line
					(at 3.81 -17.78 0)
					(length 3.81)
					(hide yes)
					(name "RSV"
						(effects
							(font
								(size 1.27 1.27)
							)
						)
					)
					(number "F2"
						(effects
							(font
								(size 1.27 1.27)
							)
						)
					)
				)
				(pin bidirectional line
					(at 31.75 0 180)
					(length 3.81)
					(name "DVB_ASI"
						(effects
							(font
								(size 1.27 1.27)
							)
						)
					)
					(number "G8"
						(effects
							(font
								(size 1.27 1.27)
							)
						)
					)
				)
				(pin bidirectional line
					(at 31.75 -2.54 180)
					(length 3.81)
					(name "~{SMPTE_BYPASS}"
						(effects
							(font
								(size 1.27 1.27)
							)
						)
					)
					(number "G7"
						(effects
							(font
								(size 1.27 1.27)
							)
						)
					)
				)
				(pin input line
					(at 31.75 -5.08 180)
					(length 3.81)
					(name "20BIT/~{10BIT}"
						(effects
							(font
								(size 1.27 1.27)
							)
						)
					)
					(number "H7"
						(effects
							(font
								(size 1.27 1.27)
							)
						)
					)
				)
				(pin input line
					(at 31.75 -7.62 180)
					(length 3.81)
					(name "AUDIO_EN/~{DIS}"
						(effects
							(font
								(size 1.27 1.27)
							)
						)
					)
					(number "H3"
						(effects
							(font
								(size 1.27 1.27)
							)
						)
					)
				)
				(pin input line
					(at 31.75 -10.16 180)
					(length 3.81)
					(name "~{CS}_TMS"
						(effects
							(font
								(size 1.27 1.27)
							)
						)
					)
					(number "F7"
						(effects
							(font
								(size 1.27 1.27)
							)
						)
					)
				)
				(pin input line
					(at 31.75 -12.7 180)
					(length 3.81)
					(name "IOPROC_EN/~{DIS}"
						(effects
							(font
								(size 1.27 1.27)
							)
						)
					)
					(number "H8"
						(effects
							(font
								(size 1.27 1.27)
							)
						)
					)
				)
				(pin input line
					(at 31.75 -15.24 180)
					(length 3.81)
					(name "JTAG/~{HOST}"
						(effects
							(font
								(size 1.27 1.27)
							)
						)
					)
					(number "D8"
						(effects
							(font
								(size 1.27 1.27)
							)
						)
					)
				)
				(pin input line
					(at 31.75 -17.78 180)
					(length 3.81)
					(name "~{RC_BYP}"
						(effects
							(font
								(size 1.27 1.27)
							)
						)
					)
					(number "G3"
						(effects
							(font
								(size 1.27 1.27)
							)
						)
					)
				)
				(pin input line
					(at 31.75 -20.32 180)
					(length 3.81)
					(name "RESET_TRST"
						(effects
							(font
								(size 1.27 1.27)
							)
						)
					)
					(number "C7"
						(effects
							(font
								(size 1.27 1.27)
							)
						)
					)
				)
				(pin input line
					(at 31.75 -22.86 180)
					(length 3.81)
					(name "SCLK_TCK"
						(effects
							(font
								(size 1.27 1.27)
							)
						)
					)
					(number "F8"
						(effects
							(font
								(size 1.27 1.27)
							)
						)
					)
				)
				(pin input line
					(at 31.75 -25.4 180)
					(length 3.81)
					(name "SDIN_TDI"
						(effects
							(font
								(size 1.27 1.27)
							)
						)
					)
					(number "E8"
						(effects
							(font
								(size 1.27 1.27)
							)
						)
					)
				)
				(pin input line
					(at 31.75 -27.94 180)
					(length 3.81)
					(name "SDO_EN/DIS"
						(effects
							(font
								(size 1.27 1.27)
							)
						)
					)
					(number "J2"
						(effects
							(font
								(size 1.27 1.27)
							)
						)
					)
				)
				(pin input line
					(at 31.75 -30.48 180)
					(length 3.81)
					(name "STANDBY"
						(effects
							(font
								(size 1.27 1.27)
							)
						)
					)
					(number "K2"
						(effects
							(font
								(size 1.27 1.27)
							)
						)
					)
				)
				(pin input line
					(at 31.75 -33.02 180)
					(length 3.81)
					(name "SW_EN"
						(effects
							(font
								(size 1.27 1.27)
							)
						)
					)
					(number "D7"
						(effects
							(font
								(size 1.27 1.27)
							)
						)
					)
				)
				(pin input line
					(at 31.75 -35.56 180)
					(length 3.81)
					(name "TIM_861"
						(effects
							(font
								(size 1.27 1.27)
							)
						)
					)
					(number "H5"
						(effects
							(font
								(size 1.27 1.27)
							)
						)
					)
				)
				(pin output line
					(at 31.75 -38.1 180)
					(length 3.81)
					(name "SDOUT_TDO"
						(effects
							(font
								(size 1.27 1.27)
							)
						)
					)
					(number "E7"
						(effects
							(font
								(size 1.27 1.27)
							)
						)
					)
				)
			)
			(symbol "GS2971A_3_1"
				(rectangle
					(start 3.81 2.54)
					(end 22.86 -17.78)
					(stroke
						(width 0.254)
						(type default)
					)
					(fill
						(type background)
					)
				)
				(pin power_in line
					(at 0 0 0)
					(length 3.81)
					(name "VCO_{VDD}"
						(effects
							(font
								(size 1.27 1.27)
							)
						)
					)
					(number "A4"
						(effects
							(font
								(size 1.27 1.27)
							)
						)
					)
				)
				(pin power_in line
					(at 0 -2.54 0)
					(length 3.81)
					(name "PLL_{VDD}"
						(effects
							(font
								(size 1.27 1.27)
							)
						)
					)
					(number "B2"
						(effects
							(font
								(size 1.27 1.27)
							)
						)
					)
				)
				(pin passive line
					(at 0 -2.54 0)
					(length 3.81)
					(hide yes)
					(name "PLL_{VDD}"
						(effects
							(font
								(size 1.27 1.27)
							)
						)
					)
					(number "C3"
						(effects
							(font
								(size 1.27 1.27)
							)
						)
					)
				)
				(pin passive line
					(at 0 -2.54 0)
					(length 3.81)
					(hide yes)
					(name "PLL_{VDD}"
						(effects
							(font
								(size 1.27 1.27)
							)
						)
					)
					(number "C4"
						(effects
							(font
								(size 1.27 1.27)
							)
						)
					)
				)
				(pin power_in line
					(at 0 -5.08 0)
					(length 3.81)
					(name "A_{VDD}"
						(effects
							(font
								(size 1.27 1.27)
							)
						)
					)
					(number "B1"
						(effects
							(font
								(size 1.27 1.27)
							)
						)
					)
				)
				(pin power_in line
					(at 0 -7.62 0)
					(length 3.81)
					(name "EQ_{VDD}"
						(effects
							(font
								(size 1.27 1.27)
							)
						)
					)
					(number "E1"
						(effects
							(font
								(size 1.27 1.27)
							)
						)
					)
				)
				(pin power_in line
					(at 0 -10.16 0)
					(length 3.81)
					(name "BUFF_{VDD}"
						(effects
							(font
								(size 1.27 1.27)
							)
						)
					)
					(number "H1"
						(effects
							(font
								(size 1.27 1.27)
							)
						)
					)
				)
				(pin power_in line
					(at 0 -12.7 0)
					(length 3.81)
					(name "CORE_{VDD}"
						(effects
							(font
								(size 1.27 1.27)
							)
						)
					)
					(number "D6"
						(effects
							(font
								(size 1.27 1.27)
							)
						)
					)
				)
				(pin passive line
					(at 0 -12.7 0)
					(length 3.81)
					(hide yes)
					(name "CORE_{VDD}"
						(effects
							(font
								(size 1.27 1.27)
							)
						)
					)
					(number "E6"
						(effects
							(font
								(size 1.27 1.27)
							)
						)
					)
				)
				(pin passive line
					(at 0 -12.7 0)
					(length 3.81)
					(hide yes)
					(name "CORE_{VDD}"
						(effects
							(font
								(size 1.27 1.27)
							)
						)
					)
					(number "F6"
						(effects
							(font
								(size 1.27 1.27)
							)
						)
					)
				)
				(pin passive line
					(at 0 -12.7 0)
					(length 3.81)
					(hide yes)
					(name "CORE_{VDD}"
						(effects
							(font
								(size 1.27 1.27)
							)
						)
					)
					(number "G6"
						(effects
							(font
								(size 1.27 1.27)
							)
						)
					)
				)
				(pin power_in line
					(at 0 -15.24 0)
					(length 3.81)
					(name "IO_{VDD}"
						(effects
							(font
								(size 1.27 1.27)
							)
						)
					)
					(number "A7"
						(effects
							(font
								(size 1.27 1.27)
							)
						)
					)
				)
				(pin passive line
					(at 0 -15.24 0)
					(length 3.81)
					(hide yes)
					(name "IO_{VDD}"
						(effects
							(font
								(size 1.27 1.27)
							)
						)
					)
					(number "D10"
						(effects
							(font
								(size 1.27 1.27)
							)
						)
					)
				)
				(pin passive line
					(at 0 -15.24 0)
					(length 3.81)
					(hide yes)
					(name "IO_{VDD}"
						(effects
							(font
								(size 1.27 1.27)
							)
						)
					)
					(number "G10"
						(effects
							(font
								(size 1.27 1.27)
							)
						)
					)
				)
				(pin passive line
					(at 0 -15.24 0)
					(length 3.81)
					(hide yes)
					(name "IO_{VDD}"
						(effects
							(font
								(size 1.27 1.27)
							)
						)
					)
					(number "K7"
						(effects
							(font
								(size 1.27 1.27)
							)
						)
					)
				)
				(pin power_in line
					(at 26.67 0 180)
					(length 3.81)
					(name "VCO_{GND}"
						(effects
							(font
								(size 1.27 1.27)
							)
						)
					)
					(number "B4"
						(effects
							(font
								(size 1.27 1.27)
							)
						)
					)
				)
				(pin power_in line
					(at 26.67 -2.54 180)
					(length 3.81)
					(name "PLL_{GND}"
						(effects
							(font
								(size 1.27 1.27)
							)
						)
					)
					(number "D4"
						(effects
							(font
								(size 1.27 1.27)
							)
						)
					)
				)
				(pin passive line
					(at 26.67 -2.54 180)
					(length 3.81)
					(hide yes)
					(name "PLL_{GND}"
						(effects
							(font
								(size 1.27 1.27)
							)
						)
					)
					(number "E4"
						(effects
							(font
								(size 1.27 1.27)
							)
						)
					)
				)
				(pin passive line
					(at 26.67 -2.54 180)
					(length 3.81)
					(hide yes)
					(name "PLL_{GND}"
						(effects
							(font
								(size 1.27 1.27)
							)
						)
					)
					(number "F4"
						(effects
							(font
								(size 1.27 1.27)
							)
						)
					)
				)
				(pin power_in line
					(at 26.67 -5.08 180)
					(length 3.81)
					(name "A_{GND}"
						(effects
							(font
								(size 1.27 1.27)
							)
						)
					)
					(number "C2"
						(effects
							(font
								(size 1.27 1.27)
							)
						)
					)
				)
				(pin passive line
					(at 26.67 -5.08 180)
					(length 3.81)
					(hide yes)
					(name "A_{GND}"
						(effects
							(font
								(size 1.27 1.27)
							)
						)
					)
					(number "D2"
						(effects
							(font
								(size 1.27 1.27)
							)
						)
					)
				)
				(pin passive line
					(at 26.67 -5.08 180)
					(length 3.81)
					(hide yes)
					(name "A_{GND}"
						(effects
							(font
								(size 1.27 1.27)
							)
						)
					)
					(number "D3"
						(effects
							(font
								(size 1.27 1.27)
							)
						)
					)
				)
				(pin passive line
					(at 26.67 -5.08 180)
					(length 3.81)
					(hide yes)
					(name "A_{GND}"
						(effects
							(font
								(size 1.27 1.27)
							)
						)
					)
					(number "E3"
						(effects
							(font
								(size 1.27 1.27)
							)
						)
					)
				)
				(pin passive line
					(at 26.67 -5.08 180)
					(length 3.81)
					(hide yes)
					(name "A_{GND}"
						(effects
							(font
								(size 1.27 1.27)
							)
						)
					)
					(number "F3"
						(effects
							(font
								(size 1.27 1.27)
							)
						)
					)
				)
				(pin passive line
					(at 26.67 -5.08 180)
					(length 3.81)
					(hide yes)
					(name "A_{GND}"
						(effects
							(font
								(size 1.27 1.27)
							)
						)
					)
					(number "G2"
						(effects
							(font
								(size 1.27 1.27)
							)
						)
					)
				)
				(pin power_in line
					(at 26.67 -7.62 180)
					(length 3.81)
					(name "EQ_{GND}"
						(effects
							(font
								(size 1.27 1.27)
							)
						)
					)
					(number "E2"
						(effects
							(font
								(size 1.27 1.27)
							)
						)
					)
				)
				(pin power_in line
					(at 26.67 -10.16 180)
					(length 3.81)
					(name "BUFF_{GND}"
						(effects
							(font
								(size 1.27 1.27)
							)
						)
					)
					(number "H2"
						(effects
							(font
								(size 1.27 1.27)
							)
						)
					)
				)
				(pin power_in line
					(at 26.67 -12.7 180)
					(length 3.81)
					(name "CORE_{GND}"
						(effects
							(font
								(size 1.27 1.27)
							)
						)
					)
					(number "D5"
						(effects
							(font
								(size 1.27 1.27)
							)
						)
					)
				)
				(pin passive line
					(at 26.67 -12.7 180)
					(length 3.81)
					(hide yes)
					(name "CORE_{GND}"
						(effects
							(font
								(size 1.27 1.27)
							)
						)
					)
					(number "E5"
						(effects
							(font
								(size 1.27 1.27)
							)
						)
					)
				)
				(pin passive line
					(at 26.67 -12.7 180)
					(length 3.81)
					(hide yes)
					(name "CORE_{GND}"
						(effects
							(font
								(size 1.27 1.27)
							)
						)
					)
					(number "F5"
						(effects
							(font
								(size 1.27 1.27)
							)
						)
					)
				)
				(pin passive line
					(at 26.67 -12.7 180)
					(length 3.81)
					(hide yes)
					(name "CORE_{GND}"
						(effects
							(font
								(size 1.27 1.27)
							)
						)
					)
					(number "G4"
						(effects
							(font
								(size 1.27 1.27)
							)
						)
					)
				)
				(pin passive line
					(at 26.67 -12.7 180)
					(length 3.81)
					(hide yes)
					(name "CORE_{GND}"
						(effects
							(font
								(size 1.27 1.27)
							)
						)
					)
					(number "G5"
						(effects
							(font
								(size 1.27 1.27)
							)
						)
					)
				)
				(pin power_in line
					(at 26.67 -15.24 180)
					(length 3.81)
					(name "IO_{GND}"
						(effects
							(font
								(size 1.27 1.27)
							)
						)
					)
					(number "B7"
						(effects
							(font
								(size 1.27 1.27)
							)
						)
					)
				)
				(pin passive line
					(at 26.67 -15.24 180)
					(length 3.81)
					(hide yes)
					(name "IO_{GND}"
						(effects
							(font
								(size 1.27 1.27)
							)
						)
					)
					(number "D9"
						(effects
							(font
								(size 1.27 1.27)
							)
						)
					)
				)
				(pin passive line
					(at 26.67 -15.24 180)
					(length 3.81)
					(hide yes)
					(name "IO_{GND}"
						(effects
							(font
								(size 1.27 1.27)
							)
						)
					)
					(number "G9"
						(effects
							(font
								(size 1.27 1.27)
							)
						)
					)
				)
				(pin passive line
					(at 26.67 -15.24 180)
					(length 3.81)
					(hide yes)
					(name "IO_{GND}"
						(effects
							(font
								(size 1.27 1.27)
							)
						)
					)
					(number "J7"
						(effects
							(font
								(size 1.27 1.27)
							)
						)
					)
				)
			)
		)
	(symbol "antmicroInterfaceControllers:GS2988"
			(exclude_from_sim no)
			(in_bom yes)
			(on_board yes)
			(property "Reference" "U"
				(at 43.18 -5.08 0)
				(effects
					(font
						(size 1.27 1.27)
						(thickness 0.15)
					)
					(justify left bottom)
				)
			)
			(property "Value" "GS2988"
				(at 43.18 -10.16 0)
				(effects
					(font
						(size 1.27 1.27)
						(thickness 0.15)
					)
					(justify left bottom)
					(hide yes)
				)
			)
			(property "Footprint" "antmicro-footprints:QFN-16-1EP_4x4mm_P0.65mm"
				(at 43.18 -12.7 0)
				(effects
					(font
						(size 1.27 1.27)
						(thickness 0.15)
					)
					(justify left bottom)
					(hide yes)
				)
			)
			(property "Datasheet" "https://semtech.my.salesforce.com/sfc/p/#E0000000JelG/a/44000000MDIY/URmNPYk6YrvngFjCh2n.ZRVsjLb90QOH1YLezdH9vhM"
				(at 43.18 -15.24 0)
				(effects
					(font
						(size 1.27 1.27)
						(thickness 0.15)
					)
					(justify left bottom)
					(hide yes)
				)
			)
			(property "Description" "SDI driver"
				(at 43.18 -25.4 0)
				(effects
					(font
						(size 1.27 1.27)
					)
					(justify left bottom)
					(hide yes)
				)
			)
			(property "MPN" "GS2988-INE3"
				(at 43.18 -7.62 0)
				(effects
					(font
						(size 1.27 1.27)
						(thickness 0.15)
					)
					(justify left bottom)
				)
			)
			(property "Manufacturer" "Semtech"
				(at 43.18 -17.78 0)
				(effects
					(font
						(size 1.27 1.27)
						(thickness 0.15)
					)
					(justify left bottom)
					(hide yes)
				)
			)
			(property "Author" "Antmicro"
				(at 43.18 -20.32 0)
				(effects
					(font
						(size 1.27 1.27)
						(thickness 0.15)
					)
					(justify left bottom)
					(hide yes)
				)
			)
			(property "License" "Apache-2.0"
				(at 43.18 -22.86 0)
				(effects
					(font
						(size 1.27 1.27)
						(thickness 0.15)
					)
					(justify left bottom)
					(hide yes)
				)
			)
			(property "ki_keywords" "IC"
				(at 0 0 0)
				(effects
					(font
						(size 1.27 1.27)
					)
					(hide yes)
				)
			)
			(symbol "GS2988_0_1"
				(rectangle
					(start 2.54 2.54)
					(end 20.32 -24.13)
					(stroke
						(width 0.254)
						(type default)
					)
					(fill
						(type background)
					)
				)
				(polyline
					(pts
						(xy 8.128 -3.81) (xy 8.89 -3.81)
					)
					(stroke
						(width 0.254)
						(type default)
					)
					(fill
						(type none)
					)
				)
				(circle
					(center 8.382 -6.35)
					(radius 0.284)
					(stroke
						(width 0.254)
						(type default)
					)
					(fill
						(type none)
					)
				)
				(polyline
					(pts
						(xy 11.43 -3.81) (xy 13.97 -3.81)
					)
					(stroke
						(width 0.254)
						(type default)
					)
					(fill
						(type none)
					)
				)
				(circle
					(center 12.065 -6.35)
					(radius 0.284)
					(stroke
						(width 0.254)
						(type default)
					)
					(fill
						(type none)
					)
				)
				(polyline
					(pts
						(xy 12.446 -6.35) (xy 13.97 -6.35)
					)
					(stroke
						(width 0.254)
						(type default)
					)
					(fill
						(type none)
					)
				)
			)
			(symbol "GS2988_1_1"
				(polyline
					(pts
						(xy 8.89 -2.54) (xy 13.97 -5.08) (xy 8.89 -7.62) (xy 8.89 -2.54)
					)
					(stroke
						(width 0.254)
						(type default)
					)
					(fill
						(type background)
					)
				)
				(pin power_in line
					(at 0 0 0)
					(length 2.54)
					(name "V_{CC}"
						(effects
							(font
								(size 1.27 1.27)
							)
						)
					)
					(number "9"
						(effects
							(font
								(size 1.27 1.27)
							)
						)
					)
				)
				(pin input line
					(at 0 -3.81 0)
					(length 2.54)
					(name "DDI+"
						(effects
							(font
								(size 1.27 1.27)
							)
						)
					)
					(number "1"
						(effects
							(font
								(size 1.27 1.27)
							)
						)
					)
				)
				(pin input line
					(at 0 -6.35 0)
					(length 2.54)
					(name "DDI-"
						(effects
							(font
								(size 1.27 1.27)
							)
						)
					)
					(number "2"
						(effects
							(font
								(size 1.27 1.27)
							)
						)
					)
				)
				(pin input line
					(at 0 -10.16 0)
					(length 2.54)
					(name "~{DISABLE}"
						(effects
							(font
								(size 1.27 1.27)
							)
						)
					)
					(number "6"
						(effects
							(font
								(size 1.27 1.27)
							)
						)
					)
				)
				(pin input line
					(at 0 -12.7 0)
					(length 2.54)
					(name "SD/~{HD}"
						(effects
							(font
								(size 1.27 1.27)
							)
						)
					)
					(number "10"
						(effects
							(font
								(size 1.27 1.27)
							)
						)
					)
				)
				(pin input line
					(at 0 -15.24 0)
					(length 2.54)
					(name "~{EQ_EN}"
						(effects
							(font
								(size 1.27 1.27)
							)
						)
					)
					(number "16"
						(effects
							(font
								(size 1.27 1.27)
							)
						)
					)
				)
				(pin power_in line
					(at 0 -19.05 0)
					(length 2.54)
					(name "V_{EE}"
						(effects
							(font
								(size 1.27 1.27)
							)
						)
					)
					(number "3"
						(effects
							(font
								(size 1.27 1.27)
							)
						)
					)
				)
				(pin passive line
					(at 0 -21.59 0)
					(length 2.54)
					(name "EP"
						(effects
							(font
								(size 1.27 1.27)
							)
						)
					)
					(number "17"
						(effects
							(font
								(size 1.27 1.27)
							)
						)
					)
				)
				(pin no_connect line
					(at 20.32 -16.51 180)
					(length 2.54)
					(hide yes)
					(name "NC"
						(effects
							(font
								(size 1.27 1.27)
							)
						)
					)
					(number "5"
						(effects
							(font
								(size 1.27 1.27)
							)
						)
					)
				)
				(pin no_connect line
					(at 20.32 -17.78 180)
					(length 2.54)
					(hide yes)
					(name "NC"
						(effects
							(font
								(size 1.27 1.27)
							)
						)
					)
					(number "7"
						(effects
							(font
								(size 1.27 1.27)
							)
						)
					)
				)
				(pin no_connect line
					(at 20.32 -19.05 180)
					(length 2.54)
					(hide yes)
					(name "NC"
						(effects
							(font
								(size 1.27 1.27)
							)
						)
					)
					(number "8"
						(effects
							(font
								(size 1.27 1.27)
							)
						)
					)
				)
				(pin no_connect line
					(at 20.32 -20.32 180)
					(length 2.54)
					(hide yes)
					(name "NC"
						(effects
							(font
								(size 1.27 1.27)
							)
						)
					)
					(number "13"
						(effects
							(font
								(size 1.27 1.27)
							)
						)
					)
				)
				(pin no_connect line
					(at 20.32 -21.59 180)
					(length 2.54)
					(hide yes)
					(name "NC"
						(effects
							(font
								(size 1.27 1.27)
							)
						)
					)
					(number "15"
						(effects
							(font
								(size 1.27 1.27)
							)
						)
					)
				)
				(pin output line
					(at 22.86 -3.81 180)
					(length 2.54)
					(name "SDO+"
						(effects
							(font
								(size 1.27 1.27)
							)
						)
					)
					(number "12"
						(effects
							(font
								(size 1.27 1.27)
							)
						)
					)
				)
				(pin output line
					(at 22.86 -6.35 180)
					(length 2.54)
					(name "SDO-"
						(effects
							(font
								(size 1.27 1.27)
							)
						)
					)
					(number "11"
						(effects
							(font
								(size 1.27 1.27)
							)
						)
					)
				)
				(pin output line
					(at 22.86 -11.43 180)
					(length 2.54)
					(name "~{OSP}"
						(effects
							(font
								(size 1.27 1.27)
							)
						)
					)
					(number "14"
						(effects
							(font
								(size 1.27 1.27)
							)
						)
					)
				)
				(pin passive line
					(at 22.86 -13.97 180)
					(length 2.54)
					(name "RSET"
						(effects
							(font
								(size 1.27 1.27)
							)
						)
					)
					(number "4"
						(effects
							(font
								(size 1.27 1.27)
							)
						)
					)
				)
			)
		)
	(symbol "antmicroInterfaceDriversReceiversTransceivers:SC18IS602BIPW"
			(exclude_from_sim no)
			(in_bom yes)
			(on_board yes)
			(property "Reference" "U"
				(at 53.34 -2.54 0)
				(effects
					(font
						(size 1.27 1.27)
						(thickness 0.15)
					)
					(justify left bottom)
				)
			)
			(property "Value" "SC18IS602BIPW"
				(at 53.34 -5.08 0)
				(effects
					(font
						(size 1.27 1.27)
						(thickness 0.15)
					)
					(justify left bottom)
					(hide yes)
				)
			)
			(property "Footprint" "antmicro-footprints:TSSOP-16_4.4x5mm_P0.65mm"
				(at 53.34 -7.62 0)
				(effects
					(font
						(size 1.27 1.27)
						(thickness 0.15)
					)
					(justify left bottom)
					(hide yes)
				)
			)
			(property "Datasheet" "https://www.nxp.com/docs/en/data-sheet/SC18IS602B.pdf"
				(at 53.34 -10.16 0)
				(effects
					(font
						(size 1.27 1.27)
						(thickness 0.15)
					)
					(justify left bottom)
					(hide yes)
				)
			)
			(property "Description" "I²C Controller SPI Interface 16-TSSOP"
				(at 53.34 -22.86 0)
				(effects
					(font
						(size 1.27 1.27)
					)
					(justify left bottom)
					(hide yes)
				)
			)
			(property "Manufacturer" "NXP"
				(at 53.34 -12.7 0)
				(effects
					(font
						(size 1.27 1.27)
						(thickness 0.15)
					)
					(justify left bottom)
					(hide yes)
				)
			)
			(property "MPN" "SC18IS602BIPW"
				(at 53.34 -15.24 0)
				(effects
					(font
						(size 1.27 1.27)
						(thickness 0.15)
					)
					(justify left bottom)
				)
			)
			(property "Author" "Antmicro"
				(at 53.34 -17.78 0)
				(effects
					(font
						(size 1.27 1.27)
						(thickness 0.15)
					)
					(justify left bottom)
					(hide yes)
				)
			)
			(property "License" "Apache-2.0"
				(at 53.34 -20.32 0)
				(effects
					(font
						(size 1.27 1.27)
						(thickness 0.15)
					)
					(justify left bottom)
					(hide yes)
				)
			)
			(property "ki_keywords" "SMT, INTERFACE, IC, I2C, SPI"
				(at 0 0 0)
				(effects
					(font
						(size 1.27 1.27)
					)
					(hide yes)
				)
			)
			(symbol "SC18IS602BIPW_1_1"
				(rectangle
					(start 2.54 2.54)
					(end 25.4 -27.94)
					(stroke
						(width 0.254)
						(type default)
					)
					(fill
						(type background)
					)
				)
				(pin power_in line
					(at 0 0 0)
					(length 2.54)
					(name "V_{DD}"
						(effects
							(font
								(size 1.27 1.27)
							)
						)
					)
					(number "12"
						(effects
							(font
								(size 1.27 1.27)
							)
						)
					)
				)
				(pin input line
					(at 0 -2.54 0)
					(length 2.54)
					(name "~{RESET}"
						(effects
							(font
								(size 1.27 1.27)
							)
						)
					)
					(number "3"
						(effects
							(font
								(size 1.27 1.27)
							)
						)
					)
				)
				(pin output line
					(at 0 -7.62 0)
					(length 2.54)
					(name "~{INT}"
						(effects
							(font
								(size 1.27 1.27)
							)
						)
					)
					(number "9"
						(effects
							(font
								(size 1.27 1.27)
							)
						)
					)
				)
				(pin bidirectional line
					(at 0 -10.16 0)
					(length 2.54)
					(name "SDA"
						(effects
							(font
								(size 1.27 1.27)
							)
						)
					)
					(number "7"
						(effects
							(font
								(size 1.27 1.27)
							)
						)
					)
				)
				(pin input line
					(at 0 -12.7 0)
					(length 2.54)
					(name "SCL"
						(effects
							(font
								(size 1.27 1.27)
							)
						)
					)
					(number "8"
						(effects
							(font
								(size 1.27 1.27)
							)
						)
					)
				)
				(pin input line
					(at 0 -17.78 0)
					(length 2.54)
					(name "A0"
						(effects
							(font
								(size 1.27 1.27)
							)
						)
					)
					(number "14"
						(effects
							(font
								(size 1.27 1.27)
							)
						)
					)
				)
				(pin input line
					(at 0 -20.32 0)
					(length 2.54)
					(name "A1"
						(effects
							(font
								(size 1.27 1.27)
							)
						)
					)
					(number "15"
						(effects
							(font
								(size 1.27 1.27)
							)
						)
					)
				)
				(pin input line
					(at 0 -22.86 0)
					(length 2.54)
					(name "A2"
						(effects
							(font
								(size 1.27 1.27)
							)
						)
					)
					(number "16"
						(effects
							(font
								(size 1.27 1.27)
							)
						)
					)
				)
				(pin power_in line
					(at 0 -25.4 0)
					(length 2.54)
					(name "V_{SS}"
						(effects
							(font
								(size 1.27 1.27)
							)
						)
					)
					(number "4"
						(effects
							(font
								(size 1.27 1.27)
							)
						)
					)
				)
				(pin input line
					(at 27.94 -5.08 180)
					(length 2.54)
					(name "MISO"
						(effects
							(font
								(size 1.27 1.27)
							)
						)
					)
					(number "5"
						(effects
							(font
								(size 1.27 1.27)
							)
						)
					)
				)
				(pin output line
					(at 27.94 -7.62 180)
					(length 2.54)
					(name "MOSI"
						(effects
							(font
								(size 1.27 1.27)
							)
						)
					)
					(number "6"
						(effects
							(font
								(size 1.27 1.27)
							)
						)
					)
				)
				(pin output line
					(at 27.94 -10.16 180)
					(length 2.54)
					(name "SCLK"
						(effects
							(font
								(size 1.27 1.27)
							)
						)
					)
					(number "11"
						(effects
							(font
								(size 1.27 1.27)
							)
						)
					)
				)
				(pin bidirectional line
					(at 27.94 -15.24 180)
					(length 2.54)
					(name "GPIO0/~{SS0}"
						(effects
							(font
								(size 1.27 1.27)
							)
						)
					)
					(number "1"
						(effects
							(font
								(size 1.27 1.27)
							)
						)
					)
				)
				(pin bidirectional line
					(at 27.94 -17.78 180)
					(length 2.54)
					(name "GPIO1/~{SS1}"
						(effects
							(font
								(size 1.27 1.27)
							)
						)
					)
					(number "2"
						(effects
							(font
								(size 1.27 1.27)
							)
						)
					)
				)
				(pin bidirectional line
					(at 27.94 -20.32 180)
					(length 2.54)
					(name "GPIO2/~{SS2}"
						(effects
							(font
								(size 1.27 1.27)
							)
						)
					)
					(number "10"
						(effects
							(font
								(size 1.27 1.27)
							)
						)
					)
				)
				(pin bidirectional line
					(at 27.94 -22.86 180)
					(length 2.54)
					(name "GPIO3/~{SS3}"
						(effects
							(font
								(size 1.27 1.27)
							)
						)
					)
					(number "13"
						(effects
							(font
								(size 1.27 1.27)
							)
						)
					)
				)
			)
		)
	(symbol "antmicroLEDIndicationDiscrete:LED_G_0603_LTST-C190GKT"
			(pin_numbers
				(hide yes)
			)
			(pin_names
				(hide yes)
			)
			(exclude_from_sim no)
			(in_bom yes)
			(on_board yes)
			(property "Reference" "D"
				(at 22.86 -2.54 0)
				(effects
					(font
						(size 1.27 1.27)
						(thickness 0.15)
					)
					(justify left bottom)
				)
			)
			(property "Value" "LED_G_0603_LTST-C190GKT"
				(at 22.86 -7.62 0)
				(effects
					(font
						(size 1.27 1.27)
						(thickness 0.15)
					)
					(justify left bottom)
					(hide yes)
				)
			)
			(property "Footprint" "antmicro-footprints:LED_0603_1608Metric_G"
				(at 22.86 -10.16 0)
				(effects
					(font
						(size 1.27 1.27)
						(thickness 0.15)
					)
					(justify left bottom)
					(hide yes)
				)
			)
			(property "Datasheet" "https://media.digikey.com/pdf/Data%20Sheets/Lite-On%20PDFs/LTST-C190GKT.pdf"
				(at 22.86 -12.7 0)
				(effects
					(font
						(size 1.27 1.27)
						(thickness 0.15)
					)
					(justify left bottom)
					(hide yes)
				)
			)
			(property "Description" "LED, Green, SMD, 0603, 20 mA, 2.1 V, 569 nm"
				(at 22.86 -25.4 0)
				(effects
					(font
						(size 1.27 1.27)
					)
					(justify left bottom)
					(hide yes)
				)
			)
			(property "MPN" "LTST-C190GKT"
				(at 22.86 -15.24 0)
				(effects
					(font
						(size 1.27 1.27)
						(thickness 0.15)
					)
					(justify left bottom)
					(hide yes)
				)
			)
			(property "Manufacturer" "Lite-On"
				(at 22.86 -17.78 0)
				(effects
					(font
						(size 1.27 1.27)
						(thickness 0.15)
					)
					(justify left bottom)
					(hide yes)
				)
			)
			(property "Color" "Green"
				(at 22.86 -5.08 0)
				(effects
					(font
						(size 1.27 1.27)
					)
					(justify left bottom)
				)
			)
			(property "Author" "Antmicro"
				(at 22.86 -20.32 0)
				(effects
					(font
						(size 1.27 1.27)
						(thickness 0.15)
					)
					(justify left bottom)
					(hide yes)
				)
			)
			(property "License" "Apache-2.0"
				(at 22.86 -22.86 0)
				(effects
					(font
						(size 1.27 1.27)
						(thickness 0.15)
					)
					(justify left bottom)
					(hide yes)
				)
			)
			(property "ki_keywords" "SMT, DIODE, SEMICONDUCTOR, LED"
				(at 0 0 0)
				(effects
					(font
						(size 1.27 1.27)
					)
					(hide yes)
				)
			)
			(symbol "LED_G_0603_LTST-C190GKT_0_1"
				(polyline
					(pts
						(xy 1.905 0) (xy 0.635 0)
					)
					(stroke
						(width 0)
						(type default)
					)
					(fill
						(type none)
					)
				)
				(polyline
					(pts
						(xy 4.445 0) (xy 3.175 0)
					)
					(stroke
						(width 0)
						(type default)
					)
					(fill
						(type none)
					)
				)
			)
			(symbol "LED_G_0603_LTST-C190GKT_1_1"
				(polyline
					(pts
						(xy 1.143 2.286) (xy 1.143 1.778) (xy 1.143 2.286) (xy 1.651 2.286) (xy 1.143 2.286) (xy 2.159 1.27)
					)
					(stroke
						(width 0.254)
						(type default)
					)
					(fill
						(type none)
					)
				)
				(polyline
					(pts
						(xy 1.778 1.016) (xy 1.778 -1.016)
					)
					(stroke
						(width 0.254)
						(type default)
					)
					(fill
						(type none)
					)
				)
				(polyline
					(pts
						(xy 2.159 2.54) (xy 2.159 2.032) (xy 2.159 2.54) (xy 2.667 2.54) (xy 2.159 2.54) (xy 3.048 1.651)
					)
					(stroke
						(width 0.254)
						(type default)
					)
					(fill
						(type none)
					)
				)
				(polyline
					(pts
						(xy 3.302 1.016) (xy 3.302 -1.016) (xy 1.778 0) (xy 3.302 1.016)
					)
					(stroke
						(width 0.254)
						(type default)
					)
					(fill
						(type outline)
					)
				)
				(pin passive line
					(at 0 0 0)
					(length 0.635)
					(name "C"
						(effects
							(font
								(size 1.27 1.27)
							)
						)
					)
					(number "1"
						(effects
							(font
								(size 1.27 1.27)
							)
						)
					)
				)
				(pin passive line
					(at 5.08 0 180)
					(length 0.635)
					(name "A"
						(effects
							(font
								(size 1.27 1.27)
							)
						)
					)
					(number "2"
						(effects
							(font
								(size 1.27 1.27)
							)
						)
					)
				)
			)
		)
	(symbol "antmicroLEDIndicationDiscrete:LED_R_0603_LTST-C190KRKT"
			(pin_numbers
				(hide yes)
			)
			(pin_names
				(hide yes)
			)
			(exclude_from_sim no)
			(in_bom yes)
			(on_board yes)
			(property "Reference" "D"
				(at 22.86 -2.54 0)
				(effects
					(font
						(size 1.27 1.27)
						(thickness 0.15)
					)
					(justify left bottom)
				)
			)
			(property "Value" "LED_R_0603_LTST-C190KRKT"
				(at 22.86 -7.62 0)
				(effects
					(font
						(size 1.27 1.27)
						(thickness 0.15)
					)
					(justify left bottom)
					(hide yes)
				)
			)
			(property "Footprint" "antmicro-footprints:LED_0603_1608Metric_R"
				(at 22.86 -10.16 0)
				(effects
					(font
						(size 1.27 1.27)
						(thickness 0.15)
					)
					(justify left bottom)
					(hide yes)
				)
			)
			(property "Datasheet" "https://optoelectronics.liteon.com/upload/download/DS-22-99-0151/LTST-C190KRKT.pdf"
				(at 22.86 -12.7 0)
				(effects
					(font
						(size 1.27 1.27)
						(thickness 0.15)
					)
					(justify left bottom)
					(hide yes)
				)
			)
			(property "Description" "LED, Red, SMD, 0603, 25 mA, 2 V, 631 nm"
				(at 22.86 -25.4 0)
				(effects
					(font
						(size 1.27 1.27)
					)
					(justify left bottom)
					(hide yes)
				)
			)
			(property "MPN" "LTST-C190KRKT"
				(at 22.86 -15.24 0)
				(effects
					(font
						(size 1.27 1.27)
						(thickness 0.15)
					)
					(justify left bottom)
					(hide yes)
				)
			)
			(property "Manufacturer" "Lite-On"
				(at 22.86 -17.78 0)
				(effects
					(font
						(size 1.27 1.27)
						(thickness 0.15)
					)
					(justify left bottom)
					(hide yes)
				)
			)
			(property "Color" "Red"
				(at 22.86 -5.08 0)
				(effects
					(font
						(size 1.27 1.27)
					)
					(justify left bottom)
				)
			)
			(property "Author" "Antmicro"
				(at 22.86 -20.32 0)
				(effects
					(font
						(size 1.27 1.27)
						(thickness 0.15)
					)
					(justify left bottom)
					(hide yes)
				)
			)
			(property "License" "Apache-2.0"
				(at 22.86 -22.86 0)
				(effects
					(font
						(size 1.27 1.27)
						(thickness 0.15)
					)
					(justify left bottom)
					(hide yes)
				)
			)
			(property "ki_keywords" "SMT, DIODE, SEMICONDUCTOR, LED"
				(at 0 0 0)
				(effects
					(font
						(size 1.27 1.27)
					)
					(hide yes)
				)
			)
			(symbol "LED_R_0603_LTST-C190KRKT_0_1"
				(polyline
					(pts
						(xy 1.905 0) (xy 0.635 0)
					)
					(stroke
						(width 0)
						(type default)
					)
					(fill
						(type none)
					)
				)
				(polyline
					(pts
						(xy 4.445 0) (xy 3.175 0)
					)
					(stroke
						(width 0)
						(type default)
					)
					(fill
						(type none)
					)
				)
			)
			(symbol "LED_R_0603_LTST-C190KRKT_1_1"
				(polyline
					(pts
						(xy 1.143 2.286) (xy 1.143 1.778) (xy 1.143 2.286) (xy 1.651 2.286) (xy 1.143 2.286) (xy 2.159 1.27)
					)
					(stroke
						(width 0.254)
						(type default)
					)
					(fill
						(type none)
					)
				)
				(polyline
					(pts
						(xy 1.778 1.016) (xy 1.778 -1.016)
					)
					(stroke
						(width 0.254)
						(type default)
					)
					(fill
						(type none)
					)
				)
				(polyline
					(pts
						(xy 2.159 2.54) (xy 2.159 2.032) (xy 2.159 2.54) (xy 2.667 2.54) (xy 2.159 2.54) (xy 3.048 1.651)
					)
					(stroke
						(width 0.254)
						(type default)
					)
					(fill
						(type none)
					)
				)
				(polyline
					(pts
						(xy 3.302 1.016) (xy 3.302 -1.016) (xy 1.778 0) (xy 3.302 1.016)
					)
					(stroke
						(width 0.254)
						(type default)
					)
					(fill
						(type outline)
					)
				)
				(pin passive line
					(at 0 0 0)
					(length 0.635)
					(name "C"
						(effects
							(font
								(size 1.27 1.27)
							)
						)
					)
					(number "1"
						(effects
							(font
								(size 1.27 1.27)
							)
						)
					)
				)
				(pin passive line
					(at 5.08 0 180)
					(length 0.635)
					(name "A"
						(effects
							(font
								(size 1.27 1.27)
							)
						)
					)
					(number "2"
						(effects
							(font
								(size 1.27 1.27)
							)
						)
					)
				)
			)
		)
	(symbol "antmicroLogicSignalSwitchesMultiplexersDecoders:TMUX1574RSVR"
			(exclude_from_sim no)
			(in_bom yes)
			(on_board yes)
			(property "Reference" "U"
				(at 44.45 0 0)
				(effects
					(font
						(size 1.27 1.27)
					)
					(justify left bottom)
				)
			)
			(property "Value" "TMUX1574RSVR"
				(at 44.45 -2.54 0)
				(effects
					(font
						(size 1.27 1.27)
					)
					(justify left bottom)
					(hide yes)
				)
			)
			(property "Footprint" "antmicro-footprints:UQFN-16-1.8x2.6mm_P0.4mm_Texas_RSV0016A"
				(at 44.45 -5.08 0)
				(effects
					(font
						(size 1.27 1.27)
					)
					(justify left bottom)
					(hide yes)
				)
			)
			(property "Datasheet" "https://www.ti.com/lit/ds/symlink/tmux1574.pdf?ts=1672927977241&ref_url=https%253A%252F%252Fwww.ti.com%252Fproduct%252FTMUX1574%253FHQS%253DTI-null-null-octopart-df-pf-xrefTI-wwe"
				(at 44.45 -7.62 0)
				(effects
					(font
						(size 1.27 1.27)
					)
					(justify left bottom)
					(hide yes)
				)
			)
			(property "Description" "Analogue switch"
				(at 44.45 -20.32 0)
				(effects
					(font
						(size 1.27 1.27)
					)
					(justify left bottom)
					(hide yes)
				)
			)
			(property "MPN" "TMUX1574RSVR"
				(at 44.45 -10.16 0)
				(effects
					(font
						(size 1.27 1.27)
					)
					(justify left bottom)
				)
			)
			(property "Manufacturer" "Texas Instruments"
				(at 44.45 -12.7 0)
				(effects
					(font
						(size 1.27 1.27)
					)
					(justify left bottom)
					(hide yes)
				)
			)
			(property "License" "Apache-2.0"
				(at 44.45 -17.78 0)
				(effects
					(font
						(size 1.27 1.27)
					)
					(justify left bottom)
					(hide yes)
				)
			)
			(property "Author" "Antmicro"
				(at 44.45 -15.24 0)
				(effects
					(font
						(size 1.27 1.27)
					)
					(justify left bottom)
					(hide yes)
				)
			)
			(property "ki_keywords" "IC"
				(at 0 0 0)
				(effects
					(font
						(size 1.27 1.27)
					)
					(hide yes)
				)
			)
			(symbol "TMUX1574RSVR_0_1"
				(rectangle
					(start 2.54 5.08)
					(end 20.32 -45.72)
					(stroke
						(width 0)
						(type default)
					)
					(fill
						(type background)
					)
				)
				(polyline
					(pts
						(xy 6.35 0) (xy 8.89 0)
					)
					(stroke
						(width 0)
						(type default)
					)
					(fill
						(type none)
					)
				)
				(polyline
					(pts
						(xy 6.35 -10.16) (xy 8.89 -10.16)
					)
					(stroke
						(width 0)
						(type default)
					)
					(fill
						(type none)
					)
				)
				(polyline
					(pts
						(xy 6.35 -20.32) (xy 8.89 -20.32)
					)
					(stroke
						(width 0)
						(type default)
					)
					(fill
						(type none)
					)
				)
				(polyline
					(pts
						(xy 6.35 -30.48) (xy 8.89 -30.48)
					)
					(stroke
						(width 0)
						(type default)
					)
					(fill
						(type none)
					)
				)
				(polyline
					(pts
						(xy 8.89 0) (xy 12.7 2.54)
					)
					(stroke
						(width 0)
						(type default)
					)
					(fill
						(type none)
					)
				)
				(circle
					(center 8.89 0)
					(radius 0.508)
					(stroke
						(width 0)
						(type default)
					)
					(fill
						(type none)
					)
				)
				(polyline
					(pts
						(xy 8.89 -10.16) (xy 12.7 -7.62)
					)
					(stroke
						(width 0)
						(type default)
					)
					(fill
						(type none)
					)
				)
				(circle
					(center 8.89 -10.16)
					(radius 0.508)
					(stroke
						(width 0)
						(type default)
					)
					(fill
						(type none)
					)
				)
				(polyline
					(pts
						(xy 8.89 -20.32) (xy 12.7 -17.78)
					)
					(stroke
						(width 0)
						(type default)
					)
					(fill
						(type none)
					)
				)
				(circle
					(center 8.89 -20.32)
					(radius 0.508)
					(stroke
						(width 0)
						(type default)
					)
					(fill
						(type none)
					)
				)
				(polyline
					(pts
						(xy 8.89 -30.48) (xy 12.7 -27.94)
					)
					(stroke
						(width 0)
						(type default)
					)
					(fill
						(type none)
					)
				)
				(circle
					(center 8.89 -30.48)
					(radius 0.508)
					(stroke
						(width 0)
						(type default)
					)
					(fill
						(type none)
					)
				)
				(polyline
					(pts
						(xy 10.795 0) (xy 10.795 1.27)
					)
					(stroke
						(width 0)
						(type default)
					)
					(fill
						(type none)
					)
				)
				(polyline
					(pts
						(xy 10.795 -2.54) (xy 10.795 -1.27)
					)
					(stroke
						(width 0)
						(type default)
					)
					(fill
						(type none)
					)
				)
				(polyline
					(pts
						(xy 10.795 -5.08) (xy 10.795 -3.81)
					)
					(stroke
						(width 0)
						(type default)
					)
					(fill
						(type none)
					)
				)
				(polyline
					(pts
						(xy 10.795 -7.62) (xy 10.795 -6.35)
					)
					(stroke
						(width 0)
						(type default)
					)
					(fill
						(type none)
					)
				)
				(polyline
					(pts
						(xy 10.795 -10.16) (xy 10.795 -8.89)
					)
					(stroke
						(width 0)
						(type default)
					)
					(fill
						(type none)
					)
				)
				(polyline
					(pts
						(xy 10.795 -12.7) (xy 10.795 -11.43)
					)
					(stroke
						(width 0)
						(type default)
					)
					(fill
						(type none)
					)
				)
				(polyline
					(pts
						(xy 10.795 -15.24) (xy 10.795 -13.97)
					)
					(stroke
						(width 0)
						(type default)
					)
					(fill
						(type none)
					)
				)
				(polyline
					(pts
						(xy 10.795 -17.78) (xy 10.795 -16.51)
					)
					(stroke
						(width 0)
						(type default)
					)
					(fill
						(type none)
					)
				)
				(polyline
					(pts
						(xy 10.795 -20.32) (xy 10.795 -19.05)
					)
					(stroke
						(width 0)
						(type default)
					)
					(fill
						(type none)
					)
				)
				(polyline
					(pts
						(xy 10.795 -22.86) (xy 10.795 -21.59)
					)
					(stroke
						(width 0)
						(type default)
					)
					(fill
						(type none)
					)
				)
				(polyline
					(pts
						(xy 10.795 -25.4) (xy 10.795 -24.13)
					)
					(stroke
						(width 0)
						(type default)
					)
					(fill
						(type none)
					)
				)
				(polyline
					(pts
						(xy 10.795 -27.94) (xy 10.795 -26.67)
					)
					(stroke
						(width 0)
						(type default)
					)
					(fill
						(type none)
					)
				)
				(polyline
					(pts
						(xy 10.795 -30.48) (xy 10.795 -29.21)
					)
					(stroke
						(width 0)
						(type default)
					)
					(fill
						(type none)
					)
				)
				(polyline
					(pts
						(xy 10.795 -33.02) (xy 10.795 -31.75)
					)
					(stroke
						(width 0)
						(type default)
					)
					(fill
						(type none)
					)
				)
				(polyline
					(pts
						(xy 10.795 -35.56) (xy 10.795 -34.29)
					)
					(stroke
						(width 0)
						(type default)
					)
					(fill
						(type none)
					)
				)
				(circle
					(center 12.7 2.54)
					(radius 0.508)
					(stroke
						(width 0)
						(type default)
					)
					(fill
						(type none)
					)
				)
				(polyline
					(pts
						(xy 12.7 -2.54) (xy 15.24 -2.54)
					)
					(stroke
						(width 0)
						(type default)
					)
					(fill
						(type none)
					)
				)
				(circle
					(center 12.7 -2.54)
					(radius 0.508)
					(stroke
						(width 0)
						(type default)
					)
					(fill
						(type none)
					)
				)
				(circle
					(center 12.7 -7.62)
					(radius 0.508)
					(stroke
						(width 0)
						(type default)
					)
					(fill
						(type none)
					)
				)
				(polyline
					(pts
						(xy 12.7 -12.7) (xy 15.24 -12.7)
					)
					(stroke
						(width 0)
						(type default)
					)
					(fill
						(type none)
					)
				)
				(circle
					(center 12.7 -12.7)
					(radius 0.508)
					(stroke
						(width 0)
						(type default)
					)
					(fill
						(type none)
					)
				)
				(circle
					(center 12.7 -17.78)
					(radius 0.508)
					(stroke
						(width 0)
						(type default)
					)
					(fill
						(type none)
					)
				)
				(polyline
					(pts
						(xy 12.7 -22.86) (xy 15.24 -22.86)
					)
					(stroke
						(width 0)
						(type default)
					)
					(fill
						(type none)
					)
				)
				(circle
					(center 12.7 -22.86)
					(radius 0.508)
					(stroke
						(width 0)
						(type default)
					)
					(fill
						(type none)
					)
				)
				(circle
					(center 12.7 -27.94)
					(radius 0.508)
					(stroke
						(width 0)
						(type default)
					)
					(fill
						(type none)
					)
				)
				(polyline
					(pts
						(xy 12.7 -33.02) (xy 15.24 -33.02)
					)
					(stroke
						(width 0)
						(type default)
					)
					(fill
						(type none)
					)
				)
				(circle
					(center 12.7 -33.02)
					(radius 0.508)
					(stroke
						(width 0)
						(type default)
					)
					(fill
						(type none)
					)
				)
				(polyline
					(pts
						(xy 15.24 2.54) (xy 13.97 2.54) (xy 12.7 2.54)
					)
					(stroke
						(width 0)
						(type default)
					)
					(fill
						(type none)
					)
				)
				(polyline
					(pts
						(xy 15.24 -7.62) (xy 13.97 -7.62) (xy 12.7 -7.62)
					)
					(stroke
						(width 0)
						(type default)
					)
					(fill
						(type none)
					)
				)
				(polyline
					(pts
						(xy 15.24 -17.78) (xy 13.97 -17.78) (xy 12.7 -17.78)
					)
					(stroke
						(width 0)
						(type default)
					)
					(fill
						(type none)
					)
				)
				(polyline
					(pts
						(xy 15.24 -27.94) (xy 13.97 -27.94) (xy 12.7 -27.94)
					)
					(stroke
						(width 0)
						(type default)
					)
					(fill
						(type none)
					)
				)
				(polyline
					(pts
						(xy 15.24 -38.1) (xy 10.795 -38.1) (xy 10.795 -36.83)
					)
					(stroke
						(width 0)
						(type default)
					)
					(fill
						(type none)
					)
				)
			)
			(symbol "TMUX1574RSVR_1_1"
				(pin bidirectional line
					(at 0 0 0)
					(length 2.54)
					(name "D1"
						(effects
							(font
								(size 1.27 1.27)
							)
						)
					)
					(number "2"
						(effects
							(font
								(size 1.27 1.27)
							)
						)
					)
				)
				(pin bidirectional line
					(at 0 -10.16 0)
					(length 2.54)
					(name "D2"
						(effects
							(font
								(size 1.27 1.27)
							)
						)
					)
					(number "5"
						(effects
							(font
								(size 1.27 1.27)
							)
						)
					)
				)
				(pin bidirectional line
					(at 0 -20.32 0)
					(length 2.54)
					(name "D3"
						(effects
							(font
								(size 1.27 1.27)
							)
						)
					)
					(number "7"
						(effects
							(font
								(size 1.27 1.27)
							)
						)
					)
				)
				(pin bidirectional line
					(at 0 -30.48 0)
					(length 2.54)
					(name "D4"
						(effects
							(font
								(size 1.27 1.27)
							)
						)
					)
					(number "10"
						(effects
							(font
								(size 1.27 1.27)
							)
						)
					)
				)
				(pin power_in line
					(at 0 -38.1 0)
					(length 2.54)
					(name "VDD"
						(effects
							(font
								(size 1.27 1.27)
							)
						)
					)
					(number "14"
						(effects
							(font
								(size 1.27 1.27)
							)
						)
					)
				)
				(pin power_in line
					(at 0 -43.18 0)
					(length 2.54)
					(name "GND"
						(effects
							(font
								(size 1.27 1.27)
							)
						)
					)
					(number "6"
						(effects
							(font
								(size 1.27 1.27)
							)
						)
					)
				)
				(pin bidirectional line
					(at 22.86 2.54 180)
					(length 2.54)
					(name "S1A"
						(effects
							(font
								(size 1.27 1.27)
							)
						)
					)
					(number "16"
						(effects
							(font
								(size 1.27 1.27)
							)
						)
					)
				)
				(pin bidirectional line
					(at 22.86 -2.54 180)
					(length 2.54)
					(name "S1B"
						(effects
							(font
								(size 1.27 1.27)
							)
						)
					)
					(number "1"
						(effects
							(font
								(size 1.27 1.27)
							)
						)
					)
				)
				(pin bidirectional line
					(at 22.86 -7.62 180)
					(length 2.54)
					(name "S2A"
						(effects
							(font
								(size 1.27 1.27)
							)
						)
					)
					(number "3"
						(effects
							(font
								(size 1.27 1.27)
							)
						)
					)
				)
				(pin bidirectional line
					(at 22.86 -12.7 180)
					(length 2.54)
					(name "S2B"
						(effects
							(font
								(size 1.27 1.27)
							)
						)
					)
					(number "4"
						(effects
							(font
								(size 1.27 1.27)
							)
						)
					)
				)
				(pin bidirectional line
					(at 22.86 -17.78 180)
					(length 2.54)
					(name "S3A"
						(effects
							(font
								(size 1.27 1.27)
							)
						)
					)
					(number "9"
						(effects
							(font
								(size 1.27 1.27)
							)
						)
					)
				)
				(pin bidirectional line
					(at 22.86 -22.86 180)
					(length 2.54)
					(name "S3B"
						(effects
							(font
								(size 1.27 1.27)
							)
						)
					)
					(number "8"
						(effects
							(font
								(size 1.27 1.27)
							)
						)
					)
				)
				(pin bidirectional line
					(at 22.86 -27.94 180)
					(length 2.54)
					(name "S4A"
						(effects
							(font
								(size 1.27 1.27)
							)
						)
					)
					(number "12"
						(effects
							(font
								(size 1.27 1.27)
							)
						)
					)
				)
				(pin bidirectional line
					(at 22.86 -33.02 180)
					(length 2.54)
					(name "S4B"
						(effects
							(font
								(size 1.27 1.27)
							)
						)
					)
					(number "11"
						(effects
							(font
								(size 1.27 1.27)
							)
						)
					)
				)
				(pin input line
					(at 22.86 -38.1 180)
					(length 2.54)
					(name "SEL"
						(effects
							(font
								(size 1.27 1.27)
							)
						)
					)
					(number "15"
						(effects
							(font
								(size 1.27 1.27)
							)
						)
					)
				)
				(pin input line
					(at 22.86 -43.18 180)
					(length 2.54)
					(name "~{EN}"
						(effects
							(font
								(size 1.27 1.27)
							)
						)
					)
					(number "13"
						(effects
							(font
								(size 1.27 1.27)
							)
						)
					)
				)
			)
		)
	(symbol "antmicroMechanicalParts:MP_Pad5.4mm_Drill2.7mm"
			(pin_names
				(hide yes)
			)
			(exclude_from_sim no)
			(in_bom no)
			(on_board yes)
			(property "Reference" "MP"
				(at 20.32 -2.54 0)
				(effects
					(font
						(size 1.27 1.27)
						(thickness 0.15)
					)
					(justify left bottom)
				)
			)
			(property "Value" "MP_Pad5.4mm_Drill2.7mm"
				(at 20.32 -5.08 0)
				(effects
					(font
						(size 1.27 1.27)
						(thickness 0.15)
					)
					(justify left bottom)
				)
			)
			(property "Footprint" "antmicro-footprints:MP_Pad5.4mm_Drill2.7mm"
				(at 20.32 -7.62 0)
				(effects
					(font
						(size 1.27 1.27)
						(thickness 0.15)
					)
					(justify left bottom)
					(hide yes)
				)
			)
			(property "Datasheet" ""
				(at 16.84 -15.57 0)
				(effects
					(font
						(size 1.27 1.27)
						(thickness 0.15)
					)
					(justify left bottom)
					(hide yes)
				)
			)
			(property "Description" "Mechanical part"
				(at 20.32 -15.24 0)
				(effects
					(font
						(size 1.27 1.27)
					)
					(justify left bottom)
					(hide yes)
				)
			)
			(property "Author" "Antmicro"
				(at 20.32 -10.16 0)
				(effects
					(font
						(size 1.27 1.27)
						(thickness 0.15)
					)
					(justify left bottom)
					(hide yes)
				)
			)
			(property "License" "Apache-2.0"
				(at 20.32 -12.7 0)
				(effects
					(font
						(size 1.27 1.27)
						(thickness 0.15)
					)
					(justify left bottom)
					(hide yes)
				)
			)
			(property "ki_keywords" "MECHANICAL"
				(at 0 0 0)
				(effects
					(font
						(size 1.27 1.27)
					)
					(hide yes)
				)
			)
			(symbol "MP_Pad5.4mm_Drill2.7mm_1_1"
				(circle
					(center 5.08 0)
					(radius 1.27)
					(stroke
						(width 0.254)
						(type default)
					)
					(fill
						(type background)
					)
				)
				(circle
					(center 5.08 0)
					(radius 2.54)
					(stroke
						(width 0.254)
						(type default)
					)
					(fill
						(type background)
					)
				)
				(pin passive line
					(at 0 0 0)
					(length 2.54)
					(name "~"
						(effects
							(font
								(size 1.27 1.27)
							)
						)
					)
					(number "1"
						(effects
							(font
								(size 1.27 1.27)
							)
						)
					)
				)
			)
		)
	(symbol "antmicroMemory:MT41K128M16JT-125_K"
			(exclude_from_sim no)
			(in_bom yes)
			(on_board yes)
			(property "Reference" "U"
				(at 50.8 -5.08 0)
				(effects
					(font
						(size 1.27 1.27)
						(thickness 0.15)
					)
					(justify left bottom)
				)
			)
			(property "Value" "MT41K128M16JT-125_K"
				(at 50.8 -7.62 0)
				(effects
					(font
						(size 1.27 1.27)
						(thickness 0.15)
					)
					(justify left bottom)
					(hide yes)
				)
			)
			(property "Footprint" "antmicro-footprints:BGA-96-48_8x14mm_Layout16x9_P0.8mm"
				(at 50.8 -10.16 0)
				(effects
					(font
						(size 1.27 1.27)
						(thickness 0.15)
					)
					(justify left bottom)
					(hide yes)
				)
			)
			(property "Datasheet" "https://www.mouser.com/datasheet/2/671/mict_s_a0002296722_1-2290882.pdf"
				(at 50.8 -12.7 0)
				(effects
					(font
						(size 1.27 1.27)
						(thickness 0.15)
					)
					(justify left bottom)
					(hide yes)
				)
			)
			(property "Description" "SDRAM - DDR3L Memory IC 2Gbit Parallel 800 MHz 13.75 ns 96-FBGA (8x14)"
				(at 50.8 -25.4 0)
				(effects
					(font
						(size 1.27 1.27)
					)
					(justify left bottom)
					(hide yes)
				)
			)
			(property "Manufacturer" "Micron Technology"
				(at 50.8 -15.24 0)
				(effects
					(font
						(size 1.27 1.27)
						(thickness 0.15)
					)
					(justify left bottom)
					(hide yes)
				)
			)
			(property "MPN" "MT41K128M16JT-125:K"
				(at 50.8 -17.78 0)
				(effects
					(font
						(size 1.27 1.27)
						(thickness 0.15)
					)
					(justify left bottom)
				)
			)
			(property "Author" "Antmicro"
				(at 50.8 -20.32 0)
				(effects
					(font
						(size 1.27 1.27)
						(thickness 0.15)
					)
					(justify left bottom)
					(hide yes)
				)
			)
			(property "License" "Apache-2.0"
				(at 50.8 -22.86 0)
				(effects
					(font
						(size 1.27 1.27)
						(thickness 0.15)
					)
					(justify left bottom)
					(hide yes)
				)
			)
			(property "ki_locked" ""
				(at 0 0 0)
				(effects
					(font
						(size 1.27 1.27)
					)
				)
			)
			(property "ki_keywords" "SMT, DRAM, IC"
				(at 0 0 0)
				(effects
					(font
						(size 1.27 1.27)
					)
					(hide yes)
				)
			)
			(symbol "MT41K128M16JT-125_K_1_1"
				(rectangle
					(start 2.54 2.54)
					(end 33.02 -81.28)
					(stroke
						(width 0.254)
						(type default)
					)
					(fill
						(type background)
					)
				)
				(pin input line
					(at 0 0 0)
					(length 2.54)
					(name "~{RESET}"
						(effects
							(font
								(size 1.27 1.27)
							)
						)
					)
					(number "T2"
						(effects
							(font
								(size 1.27 1.27)
							)
						)
					)
				)
				(pin input line
					(at 0 -2.54 0)
					(length 2.54)
					(name "~{RAS}"
						(effects
							(font
								(size 1.27 1.27)
							)
						)
					)
					(number "J3"
						(effects
							(font
								(size 1.27 1.27)
							)
						)
					)
				)
				(pin input line
					(at 0 -5.08 0)
					(length 2.54)
					(name "~{CAS}"
						(effects
							(font
								(size 1.27 1.27)
							)
						)
					)
					(number "K3"
						(effects
							(font
								(size 1.27 1.27)
							)
						)
					)
				)
				(pin input line
					(at 0 -7.62 0)
					(length 2.54)
					(name "~{WE}"
						(effects
							(font
								(size 1.27 1.27)
							)
						)
					)
					(number "L3"
						(effects
							(font
								(size 1.27 1.27)
							)
						)
					)
				)
				(pin input line
					(at 0 -10.16 0)
					(length 2.54)
					(name "~{CS}"
						(effects
							(font
								(size 1.27 1.27)
							)
						)
					)
					(number "L2"
						(effects
							(font
								(size 1.27 1.27)
							)
						)
					)
				)
				(pin input line
					(at 0 -15.24 0)
					(length 2.54)
					(name "ODT"
						(effects
							(font
								(size 1.27 1.27)
							)
						)
					)
					(number "K1"
						(effects
							(font
								(size 1.27 1.27)
							)
						)
					)
				)
				(pin input line
					(at 0 -17.78 0)
					(length 2.54)
					(name "LDM"
						(effects
							(font
								(size 1.27 1.27)
							)
						)
					)
					(number "E7"
						(effects
							(font
								(size 1.27 1.27)
							)
						)
					)
				)
				(pin input line
					(at 0 -20.32 0)
					(length 2.54)
					(name "UDM"
						(effects
							(font
								(size 1.27 1.27)
							)
						)
					)
					(number "D3"
						(effects
							(font
								(size 1.27 1.27)
							)
						)
					)
				)
				(pin input line
					(at 0 -25.4 0)
					(length 2.54)
					(name "CKE"
						(effects
							(font
								(size 1.27 1.27)
							)
						)
					)
					(number "K9"
						(effects
							(font
								(size 1.27 1.27)
							)
						)
					)
				)
				(pin input clock
					(at 0 -27.94 0)
					(length 2.54)
					(name "CK"
						(effects
							(font
								(size 1.27 1.27)
							)
						)
					)
					(number "J7"
						(effects
							(font
								(size 1.27 1.27)
							)
						)
					)
				)
				(pin input clock
					(at 0 -30.48 0)
					(length 2.54)
					(name "~{CK}"
						(effects
							(font
								(size 1.27 1.27)
							)
						)
					)
					(number "K7"
						(effects
							(font
								(size 1.27 1.27)
							)
						)
					)
				)
				(pin input line
					(at 0 -34.29 0)
					(length 2.54)
					(name "A0"
						(effects
							(font
								(size 1.27 1.27)
							)
						)
					)
					(number "N3"
						(effects
							(font
								(size 1.27 1.27)
							)
						)
					)
				)
				(pin input line
					(at 0 -38.1 0)
					(length 2.54)
					(name "A1"
						(effects
							(font
								(size 1.27 1.27)
							)
						)
					)
					(number "P7"
						(effects
							(font
								(size 1.27 1.27)
							)
						)
					)
				)
				(pin input line
					(at 0 -40.64 0)
					(length 2.54)
					(name "A2"
						(effects
							(font
								(size 1.27 1.27)
							)
						)
					)
					(number "P3"
						(effects
							(font
								(size 1.27 1.27)
							)
						)
					)
				)
				(pin input line
					(at 0 -43.18 0)
					(length 2.54)
					(name "A3"
						(effects
							(font
								(size 1.27 1.27)
							)
						)
					)
					(number "N2"
						(effects
							(font
								(size 1.27 1.27)
							)
						)
					)
				)
				(pin input line
					(at 0 -45.72 0)
					(length 2.54)
					(name "A4"
						(effects
							(font
								(size 1.27 1.27)
							)
						)
					)
					(number "P8"
						(effects
							(font
								(size 1.27 1.27)
							)
						)
					)
				)
				(pin input line
					(at 0 -48.26 0)
					(length 2.54)
					(name "A5"
						(effects
							(font
								(size 1.27 1.27)
							)
						)
					)
					(number "P2"
						(effects
							(font
								(size 1.27 1.27)
							)
						)
					)
				)
				(pin input line
					(at 0 -50.8 0)
					(length 2.54)
					(name "A6"
						(effects
							(font
								(size 1.27 1.27)
							)
						)
					)
					(number "R8"
						(effects
							(font
								(size 1.27 1.27)
							)
						)
					)
				)
				(pin input line
					(at 0 -53.34 0)
					(length 2.54)
					(name "A7"
						(effects
							(font
								(size 1.27 1.27)
							)
						)
					)
					(number "R2"
						(effects
							(font
								(size 1.27 1.27)
							)
						)
					)
				)
				(pin input line
					(at 0 -55.88 0)
					(length 2.54)
					(name "A8"
						(effects
							(font
								(size 1.27 1.27)
							)
						)
					)
					(number "T8"
						(effects
							(font
								(size 1.27 1.27)
							)
						)
					)
				)
				(pin input line
					(at 0 -58.42 0)
					(length 2.54)
					(name "A9"
						(effects
							(font
								(size 1.27 1.27)
							)
						)
					)
					(number "R3"
						(effects
							(font
								(size 1.27 1.27)
							)
						)
					)
				)
				(pin input line
					(at 0 -60.96 0)
					(length 2.54)
					(name "A10/AP"
						(effects
							(font
								(size 1.27 1.27)
							)
						)
					)
					(number "L7"
						(effects
							(font
								(size 1.27 1.27)
							)
						)
					)
				)
				(pin input line
					(at 0 -63.5 0)
					(length 2.54)
					(name "A11"
						(effects
							(font
								(size 1.27 1.27)
							)
						)
					)
					(number "R7"
						(effects
							(font
								(size 1.27 1.27)
							)
						)
					)
				)
				(pin input line
					(at 0 -66.04 0)
					(length 2.54)
					(name "A12/~{BC}"
						(effects
							(font
								(size 1.27 1.27)
							)
						)
					)
					(number "N7"
						(effects
							(font
								(size 1.27 1.27)
							)
						)
					)
				)
				(pin input line
					(at 0 -68.58 0)
					(length 2.54)
					(name "A13"
						(effects
							(font
								(size 1.27 1.27)
							)
						)
					)
					(number "T3"
						(effects
							(font
								(size 1.27 1.27)
							)
						)
					)
				)
				(pin input line
					(at 0 -73.66 0)
					(length 2.54)
					(name "BA0"
						(effects
							(font
								(size 1.27 1.27)
							)
						)
					)
					(number "M2"
						(effects
							(font
								(size 1.27 1.27)
							)
						)
					)
				)
				(pin input line
					(at 0 -76.2 0)
					(length 2.54)
					(name "BA1"
						(effects
							(font
								(size 1.27 1.27)
							)
						)
					)
					(number "N8"
						(effects
							(font
								(size 1.27 1.27)
							)
						)
					)
				)
				(pin input line
					(at 0 -78.74 0)
					(length 2.54)
					(name "BA2"
						(effects
							(font
								(size 1.27 1.27)
							)
						)
					)
					(number "M3"
						(effects
							(font
								(size 1.27 1.27)
							)
						)
					)
				)
				(pin no_connect line
					(at 33.02 -74.93 180)
					(length 2.54)
					(hide yes)
					(name "J1"
						(effects
							(font
								(size 1.27 1.27)
							)
						)
					)
					(number "J1"
						(effects
							(font
								(size 1.27 1.27)
							)
						)
					)
				)
				(pin no_connect line
					(at 33.02 -74.93 180)
					(length 2.54)
					(hide yes)
					(name "J9"
						(effects
							(font
								(size 1.27 1.27)
							)
						)
					)
					(number "J9"
						(effects
							(font
								(size 1.27 1.27)
							)
						)
					)
				)
				(pin no_connect line
					(at 33.02 -74.93 180)
					(length 2.54)
					(hide yes)
					(name "L1"
						(effects
							(font
								(size 1.27 1.27)
							)
						)
					)
					(number "L1"
						(effects
							(font
								(size 1.27 1.27)
							)
						)
					)
				)
				(pin no_connect line
					(at 33.02 -74.93 180)
					(length 2.54)
					(hide yes)
					(name "L9"
						(effects
							(font
								(size 1.27 1.27)
							)
						)
					)
					(number "L9"
						(effects
							(font
								(size 1.27 1.27)
							)
						)
					)
				)
				(pin no_connect line
					(at 33.02 -74.93 180)
					(length 2.54)
					(hide yes)
					(name "M7"
						(effects
							(font
								(size 1.27 1.27)
							)
						)
					)
					(number "M7"
						(effects
							(font
								(size 1.27 1.27)
							)
						)
					)
				)
				(pin no_connect line
					(at 33.02 -74.93 180)
					(length 2.54)
					(hide yes)
					(name "T7"
						(effects
							(font
								(size 1.27 1.27)
							)
						)
					)
					(number "T7"
						(effects
							(font
								(size 1.27 1.27)
							)
						)
					)
				)
				(pin bidirectional line
					(at 35.56 0 180)
					(length 2.54)
					(name "LDQS"
						(effects
							(font
								(size 1.27 1.27)
							)
						)
					)
					(number "F3"
						(effects
							(font
								(size 1.27 1.27)
							)
						)
					)
				)
				(pin bidirectional line
					(at 35.56 -2.54 180)
					(length 2.54)
					(name "~{LDQS}"
						(effects
							(font
								(size 1.27 1.27)
							)
						)
					)
					(number "G3"
						(effects
							(font
								(size 1.27 1.27)
							)
						)
					)
				)
				(pin bidirectional line
					(at 35.56 -5.08 180)
					(length 2.54)
					(name "UDQS"
						(effects
							(font
								(size 1.27 1.27)
							)
						)
					)
					(number "C7"
						(effects
							(font
								(size 1.27 1.27)
							)
						)
					)
				)
				(pin bidirectional line
					(at 35.56 -7.62 180)
					(length 2.54)
					(name "~{UDQS}"
						(effects
							(font
								(size 1.27 1.27)
							)
						)
					)
					(number "B7"
						(effects
							(font
								(size 1.27 1.27)
							)
						)
					)
				)
				(pin bidirectional line
					(at 35.56 -12.7 180)
					(length 2.54)
					(name "DQ0"
						(effects
							(font
								(size 1.27 1.27)
							)
						)
					)
					(number "E3"
						(effects
							(font
								(size 1.27 1.27)
							)
						)
					)
				)
				(pin bidirectional line
					(at 35.56 -15.24 180)
					(length 2.54)
					(name "DQ1"
						(effects
							(font
								(size 1.27 1.27)
							)
						)
					)
					(number "F7"
						(effects
							(font
								(size 1.27 1.27)
							)
						)
					)
				)
				(pin bidirectional line
					(at 35.56 -17.78 180)
					(length 2.54)
					(name "DQ2"
						(effects
							(font
								(size 1.27 1.27)
							)
						)
					)
					(number "F2"
						(effects
							(font
								(size 1.27 1.27)
							)
						)
					)
				)
				(pin bidirectional line
					(at 35.56 -20.32 180)
					(length 2.54)
					(name "DQ3"
						(effects
							(font
								(size 1.27 1.27)
							)
						)
					)
					(number "F8"
						(effects
							(font
								(size 1.27 1.27)
							)
						)
					)
				)
				(pin bidirectional line
					(at 35.56 -22.86 180)
					(length 2.54)
					(name "DQ4"
						(effects
							(font
								(size 1.27 1.27)
							)
						)
					)
					(number "H3"
						(effects
							(font
								(size 1.27 1.27)
							)
						)
					)
				)
				(pin bidirectional line
					(at 35.56 -25.4 180)
					(length 2.54)
					(name "DQ5"
						(effects
							(font
								(size 1.27 1.27)
							)
						)
					)
					(number "H8"
						(effects
							(font
								(size 1.27 1.27)
							)
						)
					)
				)
				(pin bidirectional line
					(at 35.56 -27.94 180)
					(length 2.54)
					(name "DQ6"
						(effects
							(font
								(size 1.27 1.27)
							)
						)
					)
					(number "G2"
						(effects
							(font
								(size 1.27 1.27)
							)
						)
					)
				)
				(pin bidirectional line
					(at 35.56 -30.48 180)
					(length 2.54)
					(name "DQ7"
						(effects
							(font
								(size 1.27 1.27)
							)
						)
					)
					(number "H7"
						(effects
							(font
								(size 1.27 1.27)
							)
						)
					)
				)
				(pin bidirectional line
					(at 35.56 -33.02 180)
					(length 2.54)
					(name "DQ8"
						(effects
							(font
								(size 1.27 1.27)
							)
						)
					)
					(number "D7"
						(effects
							(font
								(size 1.27 1.27)
							)
						)
					)
				)
				(pin bidirectional line
					(at 35.56 -35.56 180)
					(length 2.54)
					(name "DQ9"
						(effects
							(font
								(size 1.27 1.27)
							)
						)
					)
					(number "C3"
						(effects
							(font
								(size 1.27 1.27)
							)
						)
					)
				)
				(pin bidirectional line
					(at 35.56 -38.1 180)
					(length 2.54)
					(name "DQ10"
						(effects
							(font
								(size 1.27 1.27)
							)
						)
					)
					(number "C8"
						(effects
							(font
								(size 1.27 1.27)
							)
						)
					)
				)
				(pin bidirectional line
					(at 35.56 -40.64 180)
					(length 2.54)
					(name "DQ11"
						(effects
							(font
								(size 1.27 1.27)
							)
						)
					)
					(number "C2"
						(effects
							(font
								(size 1.27 1.27)
							)
						)
					)
				)
				(pin bidirectional line
					(at 35.56 -43.18 180)
					(length 2.54)
					(name "DQ12"
						(effects
							(font
								(size 1.27 1.27)
							)
						)
					)
					(number "A7"
						(effects
							(font
								(size 1.27 1.27)
							)
						)
					)
				)
				(pin bidirectional line
					(at 35.56 -45.72 180)
					(length 2.54)
					(name "DQ13"
						(effects
							(font
								(size 1.27 1.27)
							)
						)
					)
					(number "A2"
						(effects
							(font
								(size 1.27 1.27)
							)
						)
					)
				)
				(pin bidirectional line
					(at 35.56 -48.26 180)
					(length 2.54)
					(name "DQ14"
						(effects
							(font
								(size 1.27 1.27)
							)
						)
					)
					(number "B8"
						(effects
							(font
								(size 1.27 1.27)
							)
						)
					)
				)
				(pin bidirectional line
					(at 35.56 -50.8 180)
					(length 2.54)
					(name "DQ15"
						(effects
							(font
								(size 1.27 1.27)
							)
						)
					)
					(number "A3"
						(effects
							(font
								(size 1.27 1.27)
							)
						)
					)
				)
				(pin passive line
					(at 35.56 -58.42 180)
					(length 2.54)
					(name "ZQ"
						(effects
							(font
								(size 1.27 1.27)
							)
						)
					)
					(number "L8"
						(effects
							(font
								(size 1.27 1.27)
							)
						)
					)
				)
			)
			(symbol "MT41K128M16JT-125_K_2_1"
				(rectangle
					(start 2.54 2.54)
					(end 17.78 -17.78)
					(stroke
						(width 0.254)
						(type default)
					)
					(fill
						(type background)
					)
				)
				(pin power_in line
					(at 0 0 0)
					(length 2.54)
					(name "VDD"
						(effects
							(font
								(size 1.27 1.27)
							)
						)
					)
					(number "B2"
						(effects
							(font
								(size 1.27 1.27)
							)
						)
					)
				)
				(pin passive line
					(at 0 0 0)
					(length 2.54)
					(hide yes)
					(name "VDD"
						(effects
							(font
								(size 1.27 1.27)
							)
						)
					)
					(number "D9"
						(effects
							(font
								(size 1.27 1.27)
							)
						)
					)
				)
				(pin passive line
					(at 0 0 0)
					(length 2.54)
					(hide yes)
					(name "VDD"
						(effects
							(font
								(size 1.27 1.27)
							)
						)
					)
					(number "G7"
						(effects
							(font
								(size 1.27 1.27)
							)
						)
					)
				)
				(pin passive line
					(at 0 0 0)
					(length 2.54)
					(hide yes)
					(name "VDD"
						(effects
							(font
								(size 1.27 1.27)
							)
						)
					)
					(number "K2"
						(effects
							(font
								(size 1.27 1.27)
							)
						)
					)
				)
				(pin passive line
					(at 0 0 0)
					(length 2.54)
					(hide yes)
					(name "VDD"
						(effects
							(font
								(size 1.27 1.27)
							)
						)
					)
					(number "K8"
						(effects
							(font
								(size 1.27 1.27)
							)
						)
					)
				)
				(pin passive line
					(at 0 0 0)
					(length 2.54)
					(hide yes)
					(name "VDD"
						(effects
							(font
								(size 1.27 1.27)
							)
						)
					)
					(number "N1"
						(effects
							(font
								(size 1.27 1.27)
							)
						)
					)
				)
				(pin passive line
					(at 0 0 0)
					(length 2.54)
					(hide yes)
					(name "VDD"
						(effects
							(font
								(size 1.27 1.27)
							)
						)
					)
					(number "N9"
						(effects
							(font
								(size 1.27 1.27)
							)
						)
					)
				)
				(pin passive line
					(at 0 0 0)
					(length 2.54)
					(hide yes)
					(name "VDD"
						(effects
							(font
								(size 1.27 1.27)
							)
						)
					)
					(number "R1"
						(effects
							(font
								(size 1.27 1.27)
							)
						)
					)
				)
				(pin passive line
					(at 0 0 0)
					(length 2.54)
					(hide yes)
					(name "VDD"
						(effects
							(font
								(size 1.27 1.27)
							)
						)
					)
					(number "R9"
						(effects
							(font
								(size 1.27 1.27)
							)
						)
					)
				)
				(pin power_in line
					(at 0 -2.54 0)
					(length 2.54)
					(name "VDDQ"
						(effects
							(font
								(size 1.27 1.27)
							)
						)
					)
					(number "A1"
						(effects
							(font
								(size 1.27 1.27)
							)
						)
					)
				)
				(pin passive line
					(at 0 -2.54 0)
					(length 2.54)
					(hide yes)
					(name "VDDQ"
						(effects
							(font
								(size 1.27 1.27)
							)
						)
					)
					(number "A8"
						(effects
							(font
								(size 1.27 1.27)
							)
						)
					)
				)
				(pin passive line
					(at 0 -2.54 0)
					(length 2.54)
					(hide yes)
					(name "VDDQ"
						(effects
							(font
								(size 1.27 1.27)
							)
						)
					)
					(number "C1"
						(effects
							(font
								(size 1.27 1.27)
							)
						)
					)
				)
				(pin passive line
					(at 0 -2.54 0)
					(length 2.54)
					(hide yes)
					(name "VDDQ"
						(effects
							(font
								(size 1.27 1.27)
							)
						)
					)
					(number "C9"
						(effects
							(font
								(size 1.27 1.27)
							)
						)
					)
				)
				(pin passive line
					(at 0 -2.54 0)
					(length 2.54)
					(hide yes)
					(name "VDDQ"
						(effects
							(font
								(size 1.27 1.27)
							)
						)
					)
					(number "D2"
						(effects
							(font
								(size 1.27 1.27)
							)
						)
					)
				)
				(pin passive line
					(at 0 -2.54 0)
					(length 2.54)
					(hide yes)
					(name "VDDQ"
						(effects
							(font
								(size 1.27 1.27)
							)
						)
					)
					(number "E9"
						(effects
							(font
								(size 1.27 1.27)
							)
						)
					)
				)
				(pin passive line
					(at 0 -2.54 0)
					(length 2.54)
					(hide yes)
					(name "VDDQ"
						(effects
							(font
								(size 1.27 1.27)
							)
						)
					)
					(number "F1"
						(effects
							(font
								(size 1.27 1.27)
							)
						)
					)
				)
				(pin passive line
					(at 0 -2.54 0)
					(length 2.54)
					(hide yes)
					(name "VDDQ"
						(effects
							(font
								(size 1.27 1.27)
							)
						)
					)
					(number "H2"
						(effects
							(font
								(size 1.27 1.27)
							)
						)
					)
				)
				(pin passive line
					(at 0 -2.54 0)
					(length 2.54)
					(hide yes)
					(name "VDDQ"
						(effects
							(font
								(size 1.27 1.27)
							)
						)
					)
					(number "H9"
						(effects
							(font
								(size 1.27 1.27)
							)
						)
					)
				)
				(pin power_in line
					(at 0 -6.35 0)
					(length 2.54)
					(name "VREFCA"
						(effects
							(font
								(size 1.27 1.27)
							)
						)
					)
					(number "M8"
						(effects
							(font
								(size 1.27 1.27)
							)
						)
					)
				)
				(pin power_in line
					(at 0 -8.89 0)
					(length 2.54)
					(name "VREFDQ"
						(effects
							(font
								(size 1.27 1.27)
							)
						)
					)
					(number "H1"
						(effects
							(font
								(size 1.27 1.27)
							)
						)
					)
				)
				(pin passive line
					(at 0 -12.7 0)
					(length 2.54)
					(name "VSSQ"
						(effects
							(font
								(size 1.27 1.27)
							)
						)
					)
					(number "B1"
						(effects
							(font
								(size 1.27 1.27)
							)
						)
					)
				)
				(pin passive line
					(at 0 -12.7 0)
					(length 2.54)
					(hide yes)
					(name "VSSQ"
						(effects
							(font
								(size 1.27 1.27)
							)
						)
					)
					(number "B9"
						(effects
							(font
								(size 1.27 1.27)
							)
						)
					)
				)
				(pin passive line
					(at 0 -12.7 0)
					(length 2.54)
					(hide yes)
					(name "VSSQ"
						(effects
							(font
								(size 1.27 1.27)
							)
						)
					)
					(number "D1"
						(effects
							(font
								(size 1.27 1.27)
							)
						)
					)
				)
				(pin passive line
					(at 0 -12.7 0)
					(length 2.54)
					(hide yes)
					(name "VSSQ"
						(effects
							(font
								(size 1.27 1.27)
							)
						)
					)
					(number "D8"
						(effects
							(font
								(size 1.27 1.27)
							)
						)
					)
				)
				(pin passive line
					(at 0 -12.7 0)
					(length 2.54)
					(hide yes)
					(name "VSSQ"
						(effects
							(font
								(size 1.27 1.27)
							)
						)
					)
					(number "E2"
						(effects
							(font
								(size 1.27 1.27)
							)
						)
					)
				)
				(pin passive line
					(at 0 -12.7 0)
					(length 2.54)
					(hide yes)
					(name "VSSQ"
						(effects
							(font
								(size 1.27 1.27)
							)
						)
					)
					(number "E8"
						(effects
							(font
								(size 1.27 1.27)
							)
						)
					)
				)
				(pin passive line
					(at 0 -12.7 0)
					(length 2.54)
					(hide yes)
					(name "VSSQ"
						(effects
							(font
								(size 1.27 1.27)
							)
						)
					)
					(number "F9"
						(effects
							(font
								(size 1.27 1.27)
							)
						)
					)
				)
				(pin passive line
					(at 0 -12.7 0)
					(length 2.54)
					(hide yes)
					(name "VSSQ"
						(effects
							(font
								(size 1.27 1.27)
							)
						)
					)
					(number "G1"
						(effects
							(font
								(size 1.27 1.27)
							)
						)
					)
				)
				(pin passive line
					(at 0 -12.7 0)
					(length 2.54)
					(hide yes)
					(name "VSSQ"
						(effects
							(font
								(size 1.27 1.27)
							)
						)
					)
					(number "G9"
						(effects
							(font
								(size 1.27 1.27)
							)
						)
					)
				)
				(pin passive line
					(at 0 -15.24 0)
					(length 2.54)
					(name "VSS"
						(effects
							(font
								(size 1.27 1.27)
							)
						)
					)
					(number "A9"
						(effects
							(font
								(size 1.27 1.27)
							)
						)
					)
				)
				(pin passive line
					(at 0 -15.24 0)
					(length 2.54)
					(hide yes)
					(name "VSS"
						(effects
							(font
								(size 1.27 1.27)
							)
						)
					)
					(number "B3"
						(effects
							(font
								(size 1.27 1.27)
							)
						)
					)
				)
				(pin passive line
					(at 0 -15.24 0)
					(length 2.54)
					(hide yes)
					(name "VSS"
						(effects
							(font
								(size 1.27 1.27)
							)
						)
					)
					(number "E1"
						(effects
							(font
								(size 1.27 1.27)
							)
						)
					)
				)
				(pin passive line
					(at 0 -15.24 0)
					(length 2.54)
					(hide yes)
					(name "VSS"
						(effects
							(font
								(size 1.27 1.27)
							)
						)
					)
					(number "G8"
						(effects
							(font
								(size 1.27 1.27)
							)
						)
					)
				)
				(pin passive line
					(at 0 -15.24 0)
					(length 2.54)
					(hide yes)
					(name "VSS"
						(effects
							(font
								(size 1.27 1.27)
							)
						)
					)
					(number "J2"
						(effects
							(font
								(size 1.27 1.27)
							)
						)
					)
				)
				(pin passive line
					(at 0 -15.24 0)
					(length 2.54)
					(hide yes)
					(name "VSS"
						(effects
							(font
								(size 1.27 1.27)
							)
						)
					)
					(number "J8"
						(effects
							(font
								(size 1.27 1.27)
							)
						)
					)
				)
				(pin passive line
					(at 0 -15.24 0)
					(length 2.54)
					(hide yes)
					(name "VSS"
						(effects
							(font
								(size 1.27 1.27)
							)
						)
					)
					(number "M1"
						(effects
							(font
								(size 1.27 1.27)
							)
						)
					)
				)
				(pin passive line
					(at 0 -15.24 0)
					(length 2.54)
					(hide yes)
					(name "VSS"
						(effects
							(font
								(size 1.27 1.27)
							)
						)
					)
					(number "M9"
						(effects
							(font
								(size 1.27 1.27)
							)
						)
					)
				)
				(pin passive line
					(at 0 -15.24 0)
					(length 2.54)
					(hide yes)
					(name "VSS"
						(effects
							(font
								(size 1.27 1.27)
							)
						)
					)
					(number "P1"
						(effects
							(font
								(size 1.27 1.27)
							)
						)
					)
				)
				(pin passive line
					(at 0 -15.24 0)
					(length 2.54)
					(hide yes)
					(name "VSS"
						(effects
							(font
								(size 1.27 1.27)
							)
						)
					)
					(number "P9"
						(effects
							(font
								(size 1.27 1.27)
							)
						)
					)
				)
				(pin passive line
					(at 0 -15.24 0)
					(length 2.54)
					(hide yes)
					(name "VSS"
						(effects
							(font
								(size 1.27 1.27)
							)
						)
					)
					(number "T1"
						(effects
							(font
								(size 1.27 1.27)
							)
						)
					)
				)
				(pin passive line
					(at 0 -15.24 0)
					(length 2.54)
					(hide yes)
					(name "VSS"
						(effects
							(font
								(size 1.27 1.27)
							)
						)
					)
					(number "T9"
						(effects
							(font
								(size 1.27 1.27)
							)
						)
					)
				)
			)
		)
	(symbol "antmicroMemory:W25Q32JVSNIQ"
			(exclude_from_sim no)
			(in_bom yes)
			(on_board yes)
			(property "Reference" "U"
				(at 33.02 -3.81 0)
				(effects
					(font
						(size 1.27 1.27)
						(thickness 0.15)
					)
					(justify left bottom)
				)
			)
			(property "Value" "W25Q32JVSNIQ"
				(at 33.02 -6.35 0)
				(effects
					(font
						(size 1.27 1.27)
						(thickness 0.15)
					)
					(justify left bottom)
					(hide yes)
				)
			)
			(property "Footprint" "antmicro-footprints:SOIC-8_3.9x4.9x1.75mm_P1.27mm"
				(at 33.02 -8.89 0)
				(effects
					(font
						(size 1.27 1.27)
						(thickness 0.15)
					)
					(justify left bottom)
					(hide yes)
				)
			)
			(property "Datasheet" "https://www.mouser.com/datasheet/2/949/w25q32jv_revg_03272018_plus-1489806.pdf"
				(at 33.02 -11.43 0)
				(effects
					(font
						(size 1.27 1.27)
						(thickness 0.15)
					)
					(justify left bottom)
					(hide yes)
				)
			)
			(property "Description" "Flash Memory, Serial NOR, 32 Mbit, 4M x 8bit, SPI, SOIC, 8 Pins"
				(at 33.02 -24.13 0)
				(effects
					(font
						(size 1.27 1.27)
					)
					(justify left bottom)
					(hide yes)
				)
			)
			(property "MPN" "W25Q32JVSNIQ"
				(at 33.02 -13.97 0)
				(effects
					(font
						(size 1.27 1.27)
						(thickness 0.15)
					)
					(justify left bottom)
				)
			)
			(property "Manufacturer" "Winbond"
				(at 33.02 -16.51 0)
				(effects
					(font
						(size 1.27 1.27)
						(thickness 0.15)
					)
					(justify left bottom)
					(hide yes)
				)
			)
			(property "Author" "Antmicro"
				(at 33.02 -19.05 0)
				(effects
					(font
						(size 1.27 1.27)
						(thickness 0.15)
					)
					(justify left bottom)
					(hide yes)
				)
			)
			(property "License" "Apache-2.0"
				(at 33.02 -21.59 0)
				(effects
					(font
						(size 1.27 1.27)
						(thickness 0.15)
					)
					(justify left bottom)
					(hide yes)
				)
			)
			(property "ki_keywords" "FLASH, SPI, MEMORY"
				(at 0 0 0)
				(effects
					(font
						(size 1.27 1.27)
					)
					(hide yes)
				)
			)
			(symbol "W25Q32JVSNIQ_1_1"
				(rectangle
					(start 2.54 2.54)
					(end 16.51 -15.24)
					(stroke
						(width 0.254)
						(type default)
					)
					(fill
						(type background)
					)
				)
				(pin bidirectional line
					(at 0 0 0)
					(length 2.54)
					(name "SI/IO0"
						(effects
							(font
								(size 1.27 1.27)
							)
						)
					)
					(number "5"
						(effects
							(font
								(size 1.27 1.27)
							)
						)
					)
				)
				(pin bidirectional line
					(at 0 -2.54 0)
					(length 2.54)
					(name "SO/IO1"
						(effects
							(font
								(size 1.27 1.27)
							)
						)
					)
					(number "2"
						(effects
							(font
								(size 1.27 1.27)
							)
						)
					)
				)
				(pin bidirectional line
					(at 0 -5.08 0)
					(length 2.54)
					(name "~{WP}/IO2"
						(effects
							(font
								(size 1.27 1.27)
							)
						)
					)
					(number "3"
						(effects
							(font
								(size 1.27 1.27)
							)
						)
					)
				)
				(pin bidirectional line
					(at 0 -7.62 0)
					(length 2.54)
					(name "~{HOLD}/IO3"
						(effects
							(font
								(size 1.27 1.27)
							)
						)
					)
					(number "7"
						(effects
							(font
								(size 1.27 1.27)
							)
						)
					)
				)
				(pin input line
					(at 0 -10.16 0)
					(length 2.54)
					(name "SCLK"
						(effects
							(font
								(size 1.27 1.27)
							)
						)
					)
					(number "6"
						(effects
							(font
								(size 1.27 1.27)
							)
						)
					)
				)
				(pin input line
					(at 0 -12.7 0)
					(length 2.54)
					(name "~{CS}"
						(effects
							(font
								(size 1.27 1.27)
							)
						)
					)
					(number "1"
						(effects
							(font
								(size 1.27 1.27)
							)
						)
					)
				)
				(pin power_in line
					(at 19.05 0 180)
					(length 2.54)
					(name "VCC"
						(effects
							(font
								(size 1.27 1.27)
							)
						)
					)
					(number "8"
						(effects
							(font
								(size 1.27 1.27)
							)
						)
					)
				)
				(pin power_in line
					(at 19.05 -12.7 180)
					(length 2.54)
					(name "VSS"
						(effects
							(font
								(size 1.27 1.27)
							)
						)
					)
					(number "4"
						(effects
							(font
								(size 1.27 1.27)
							)
						)
					)
				)
			)
		)
	(symbol "antmicroOperationalAmplifiers:LM339_TSSOP_CUSTOM_Split"
			(exclude_from_sim no)
			(in_bom yes)
			(on_board yes)
			(property "Reference" "U"
				(at 25.4 -5.08 0)
				(effects
					(font
						(size 1.27 1.27)
						(thickness 0.15)
					)
					(justify left bottom)
				)
			)
			(property "Value" "LM339_TSSOP_CUSTOM_Split"
				(at 25.4 -7.62 0)
				(effects
					(font
						(size 1.27 1.27)
						(thickness 0.15)
					)
					(justify left bottom)
					(hide yes)
				)
			)
			(property "Footprint" "antmicro-footprints:TSSOP-14_4.4x5mm_P0.65mm"
				(at 25.4 -10.16 0)
				(effects
					(font
						(size 1.27 1.27)
						(thickness 0.15)
					)
					(justify left bottom)
					(hide yes)
				)
			)
			(property "Datasheet" "https://www.ti.com/lit/ds/symlink/lm339b.pdf?ts=1679641364820&ref_url=https%253A%252F%252Fwww.google.com%252F"
				(at 25.4 -12.7 0)
				(effects
					(font
						(size 1.27 1.27)
						(thickness 0.15)
					)
					(justify left bottom)
					(hide yes)
				)
			)
			(property "Description" "Analogue Comparator, Differential, 4 Comparators, 300 ns, 2V to 36V, TSSOP, 14 Pins"
				(at 25.4 -25.4 0)
				(effects
					(font
						(size 1.27 1.27)
					)
					(justify left bottom)
					(hide yes)
				)
			)
			(property "MPN" "LM339PW"
				(at 25.4 -15.24 0)
				(effects
					(font
						(size 1.27 1.27)
						(thickness 0.15)
					)
					(justify left bottom)
				)
			)
			(property "Manufacturer" "Texas Instruments"
				(at 25.4 -17.78 0)
				(effects
					(font
						(size 1.27 1.27)
						(thickness 0.15)
					)
					(justify left bottom)
					(hide yes)
				)
			)
			(property "Author" "Antmicro"
				(at 25.4 -20.32 0)
				(effects
					(font
						(size 1.27 1.27)
						(thickness 0.15)
					)
					(justify left bottom)
					(hide yes)
				)
			)
			(property "License" "Apache-2.0"
				(at 25.4 -22.86 0)
				(effects
					(font
						(size 1.27 1.27)
						(thickness 0.15)
					)
					(justify left bottom)
					(hide yes)
				)
			)
			(property "ki_keywords" "SMT, AMP, IC"
				(at 0 0 0)
				(effects
					(font
						(size 1.27 1.27)
					)
					(hide yes)
				)
			)
			(symbol "LM339_TSSOP_CUSTOM_Split_1_1"
				(polyline
					(pts
						(xy 2.54 1.27) (xy 7.62 -1.27) (xy 2.54 -3.81) (xy 2.54 1.27)
					)
					(stroke
						(width 0.254)
						(type default)
					)
					(fill
						(type background)
					)
				)
				(polyline
					(pts
						(xy 4.826 -1.778) (xy 5.207 -1.778) (xy 5.461 -0.762) (xy 5.842 -0.762)
					)
					(stroke
						(width 0.127)
						(type default)
					)
					(fill
						(type background)
					)
				)
				(polyline
					(pts
						(xy 4.953 -1.27) (xy 4.826 -1.27)
					)
					(stroke
						(width 0.127)
						(type default)
					)
					(fill
						(type background)
					)
				)
				(polyline
					(pts
						(xy 5.461 -1.27) (xy 5.207 -1.27)
					)
					(stroke
						(width 0.127)
						(type default)
					)
					(fill
						(type background)
					)
				)
				(polyline
					(pts
						(xy 5.842 -1.27) (xy 5.715 -1.27)
					)
					(stroke
						(width 0.127)
						(type default)
					)
					(fill
						(type background)
					)
				)
				(text "+"
					(at 2.54 -1.016 0)
					(effects
						(font
							(size 1.27 1.27)
							(thickness 0.15)
						)
						(justify left bottom)
					)
				)
				(text "-"
					(at 2.54 -3.302 0)
					(effects
						(font
							(size 1.27 1.27)
							(thickness 0.15)
						)
						(justify left bottom)
					)
				)
				(pin input line
					(at 0 0 0)
					(length 2.54)
					(name ""
						(effects
							(font
								(size 1.27 1.27)
							)
						)
					)
					(number "5"
						(effects
							(font
								(size 1.27 1.27)
							)
						)
					)
				)
				(pin input line
					(at 0 -2.54 0)
					(length 2.54)
					(name ""
						(effects
							(font
								(size 1.27 1.27)
							)
						)
					)
					(number "4"
						(effects
							(font
								(size 1.27 1.27)
							)
						)
					)
				)
				(pin output line
					(at 10.16 -1.27 180)
					(length 2.54)
					(name ""
						(effects
							(font
								(size 1.27 1.27)
							)
						)
					)
					(number "2"
						(effects
							(font
								(size 1.27 1.27)
							)
						)
					)
				)
			)
			(symbol "LM339_TSSOP_CUSTOM_Split_2_1"
				(polyline
					(pts
						(xy 2.54 1.27) (xy 7.62 -1.27) (xy 2.54 -3.81) (xy 2.54 1.27)
					)
					(stroke
						(width 0.254)
						(type default)
					)
					(fill
						(type background)
					)
				)
				(polyline
					(pts
						(xy 4.826 -1.778) (xy 5.207 -1.778) (xy 5.461 -0.762) (xy 5.842 -0.762)
					)
					(stroke
						(width 0.127)
						(type default)
					)
					(fill
						(type background)
					)
				)
				(polyline
					(pts
						(xy 4.953 -1.27) (xy 4.826 -1.27)
					)
					(stroke
						(width 0.127)
						(type default)
					)
					(fill
						(type background)
					)
				)
				(polyline
					(pts
						(xy 5.461 -1.27) (xy 5.207 -1.27)
					)
					(stroke
						(width 0.127)
						(type default)
					)
					(fill
						(type background)
					)
				)
				(polyline
					(pts
						(xy 5.842 -1.27) (xy 5.715 -1.27)
					)
					(stroke
						(width 0.127)
						(type default)
					)
					(fill
						(type background)
					)
				)
				(text "+"
					(at 2.54 -1.016 0)
					(effects
						(font
							(size 1.27 1.27)
							(thickness 0.15)
						)
						(justify left bottom)
					)
				)
				(text "-"
					(at 2.54 -3.302 0)
					(effects
						(font
							(size 1.27 1.27)
							(thickness 0.15)
						)
						(justify left bottom)
					)
				)
				(pin input line
					(at 0 0 0)
					(length 2.54)
					(name ""
						(effects
							(font
								(size 1.27 1.27)
							)
						)
					)
					(number "7"
						(effects
							(font
								(size 1.27 1.27)
							)
						)
					)
				)
				(pin input line
					(at 0 -2.54 0)
					(length 2.54)
					(name ""
						(effects
							(font
								(size 1.27 1.27)
							)
						)
					)
					(number "6"
						(effects
							(font
								(size 1.27 1.27)
							)
						)
					)
				)
				(pin output line
					(at 10.16 -1.27 180)
					(length 2.54)
					(name ""
						(effects
							(font
								(size 1.27 1.27)
							)
						)
					)
					(number "1"
						(effects
							(font
								(size 1.27 1.27)
							)
						)
					)
				)
			)
			(symbol "LM339_TSSOP_CUSTOM_Split_3_1"
				(polyline
					(pts
						(xy 2.54 1.27) (xy 7.62 -1.27) (xy 2.54 -3.81) (xy 2.54 1.27)
					)
					(stroke
						(width 0.254)
						(type default)
					)
					(fill
						(type background)
					)
				)
				(polyline
					(pts
						(xy 4.826 -1.778) (xy 5.207 -1.778) (xy 5.461 -0.762) (xy 5.842 -0.762)
					)
					(stroke
						(width 0.127)
						(type default)
					)
					(fill
						(type background)
					)
				)
				(polyline
					(pts
						(xy 4.953 -1.27) (xy 4.826 -1.27)
					)
					(stroke
						(width 0.127)
						(type default)
					)
					(fill
						(type background)
					)
				)
				(polyline
					(pts
						(xy 5.461 -1.27) (xy 5.207 -1.27)
					)
					(stroke
						(width 0.127)
						(type default)
					)
					(fill
						(type background)
					)
				)
				(polyline
					(pts
						(xy 5.842 -1.27) (xy 5.715 -1.27)
					)
					(stroke
						(width 0.127)
						(type default)
					)
					(fill
						(type background)
					)
				)
				(text "+"
					(at 2.54 -1.016 0)
					(effects
						(font
							(size 1.27 1.27)
							(thickness 0.15)
						)
						(justify left bottom)
					)
				)
				(text "-"
					(at 2.54 -3.302 0)
					(effects
						(font
							(size 1.27 1.27)
							(thickness 0.15)
						)
						(justify left bottom)
					)
				)
				(pin input line
					(at 0 0 0)
					(length 2.54)
					(name ""
						(effects
							(font
								(size 1.27 1.27)
							)
						)
					)
					(number "9"
						(effects
							(font
								(size 1.27 1.27)
							)
						)
					)
				)
				(pin input line
					(at 0 -2.54 0)
					(length 2.54)
					(name ""
						(effects
							(font
								(size 1.27 1.27)
							)
						)
					)
					(number "8"
						(effects
							(font
								(size 1.27 1.27)
							)
						)
					)
				)
				(pin output line
					(at 10.16 -1.27 180)
					(length 2.54)
					(name ""
						(effects
							(font
								(size 1.27 1.27)
							)
						)
					)
					(number "14"
						(effects
							(font
								(size 1.27 1.27)
							)
						)
					)
				)
			)
			(symbol "LM339_TSSOP_CUSTOM_Split_4_1"
				(polyline
					(pts
						(xy 2.54 1.27) (xy 7.62 -1.27) (xy 2.54 -3.81) (xy 2.54 1.27)
					)
					(stroke
						(width 0.254)
						(type default)
					)
					(fill
						(type background)
					)
				)
				(polyline
					(pts
						(xy 4.826 -1.778) (xy 5.207 -1.778) (xy 5.461 -0.762) (xy 5.842 -0.762)
					)
					(stroke
						(width 0.127)
						(type default)
					)
					(fill
						(type background)
					)
				)
				(polyline
					(pts
						(xy 4.953 -1.27) (xy 4.826 -1.27)
					)
					(stroke
						(width 0.127)
						(type default)
					)
					(fill
						(type background)
					)
				)
				(polyline
					(pts
						(xy 5.461 -1.27) (xy 5.207 -1.27)
					)
					(stroke
						(width 0.127)
						(type default)
					)
					(fill
						(type background)
					)
				)
				(polyline
					(pts
						(xy 5.842 -1.27) (xy 5.715 -1.27)
					)
					(stroke
						(width 0.127)
						(type default)
					)
					(fill
						(type background)
					)
				)
				(text "+"
					(at 2.54 -1.016 0)
					(effects
						(font
							(size 1.27 1.27)
							(thickness 0.15)
						)
						(justify left bottom)
					)
				)
				(text "-"
					(at 2.54 -3.302 0)
					(effects
						(font
							(size 1.27 1.27)
							(thickness 0.15)
						)
						(justify left bottom)
					)
				)
				(pin input line
					(at 0 0 0)
					(length 2.54)
					(name ""
						(effects
							(font
								(size 1.27 1.27)
							)
						)
					)
					(number "11"
						(effects
							(font
								(size 1.27 1.27)
							)
						)
					)
				)
				(pin input line
					(at 0 -2.54 0)
					(length 2.54)
					(name ""
						(effects
							(font
								(size 1.27 1.27)
							)
						)
					)
					(number "10"
						(effects
							(font
								(size 1.27 1.27)
							)
						)
					)
				)
				(pin output line
					(at 10.16 -1.27 180)
					(length 2.54)
					(name ""
						(effects
							(font
								(size 1.27 1.27)
							)
						)
					)
					(number "13"
						(effects
							(font
								(size 1.27 1.27)
							)
						)
					)
				)
			)
			(symbol "LM339_TSSOP_CUSTOM_Split_5_1"
				(rectangle
					(start 2.54 1.27)
					(end 7.62 -3.81)
					(stroke
						(width 0.254)
						(type default)
					)
					(fill
						(type background)
					)
				)
				(polyline
					(pts
						(xy 5.842 -1.778) (xy 6.223 -1.778) (xy 6.477 -0.762) (xy 6.858 -0.762)
					)
					(stroke
						(width 0.127)
						(type default)
					)
					(fill
						(type background)
					)
				)
				(polyline
					(pts
						(xy 5.969 -1.27) (xy 5.842 -1.27)
					)
					(stroke
						(width 0.127)
						(type default)
					)
					(fill
						(type background)
					)
				)
				(polyline
					(pts
						(xy 6.477 -1.27) (xy 6.223 -1.27)
					)
					(stroke
						(width 0.127)
						(type default)
					)
					(fill
						(type background)
					)
				)
				(polyline
					(pts
						(xy 6.858 -1.27) (xy 6.731 -1.27)
					)
					(stroke
						(width 0.127)
						(type default)
					)
					(fill
						(type background)
					)
				)
				(pin power_in line
					(at 0 0 0)
					(length 2.54)
					(name "V+"
						(effects
							(font
								(size 1.27 1.27)
							)
						)
					)
					(number "3"
						(effects
							(font
								(size 1.27 1.27)
							)
						)
					)
				)
				(pin power_in line
					(at 0 -2.54 0)
					(length 2.54)
					(name "V-"
						(effects
							(font
								(size 1.27 1.27)
							)
						)
					)
					(number "12"
						(effects
							(font
								(size 1.27 1.27)
							)
						)
					)
				)
			)
		)
	(symbol "antmicroOscillators:Oscillator_40MHz_YIC_OSC-S5"
			(exclude_from_sim no)
			(in_bom yes)
			(on_board yes)
			(property "Reference" "Y"
				(at 25.4 -1.905 0)
				(effects
					(font
						(size 1.27 1.27)
						(thickness 0.15)
					)
					(justify left bottom)
				)
			)
			(property "Value" "Oscillator_40MHz_YIC_OSC-S5"
				(at 25.4 -12.065 0)
				(effects
					(font
						(size 1.27 1.27)
						(thickness 0.15)
					)
					(justify left bottom)
					(hide yes)
				)
			)
			(property "Footprint" "antmicro-footprints:Oscillator_SMD_YIC_OSC-S5_5x3.2mm"
				(at 25.4 -14.605 0)
				(effects
					(font
						(size 1.27 1.27)
						(thickness 0.15)
					)
					(justify left bottom)
					(hide yes)
				)
			)
			(property "Datasheet" "https://www.tme.eu/Document/456c7b2975a812de7905406dd4f750d9/YIC-S5.pdf"
				(at 25.4 -17.145 0)
				(effects
					(font
						(size 1.27 1.27)
						(thickness 0.15)
					)
					(justify left bottom)
					(hide yes)
				)
			)
			(property "Description" "Generator: quartz, 40MHz, SMD, 3.3V, ±50ppm, -20÷70°C, 5x3.2x1.3mm"
				(at 25.4 -24.765 0)
				(effects
					(font
						(size 1.27 1.27)
					)
					(justify left bottom)
					(hide yes)
				)
			)
			(property "MPN" "OSC40M-3.3/S5"
				(at 25.4 -4.445 0)
				(effects
					(font
						(size 1.27 1.27)
						(thickness 0.15)
					)
					(justify left bottom)
				)
			)
			(property "Manufacturer" "YIC"
				(at 25.4 -6.985 0)
				(effects
					(font
						(size 1.27 1.27)
						(thickness 0.15)
					)
					(justify left bottom)
					(hide yes)
				)
			)
			(property "Val" "40 MHz"
				(at 25.4 -9.525 0)
				(effects
					(font
						(size 1.27 1.27)
						(thickness 0.15)
					)
					(justify left bottom)
				)
			)
			(property "Author" "Antmicro"
				(at 25.4 -19.685 0)
				(effects
					(font
						(size 1.27 1.27)
						(thickness 0.15)
					)
					(justify left bottom)
					(hide yes)
				)
			)
			(property "License" "Apache-2.0"
				(at 25.4 -22.225 0)
				(effects
					(font
						(size 1.27 1.27)
						(thickness 0.15)
					)
					(justify left bottom)
					(hide yes)
				)
			)
			(property "ki_keywords" "OSCILLATOR"
				(at 0 0 0)
				(effects
					(font
						(size 1.27 1.27)
					)
					(hide yes)
				)
			)
			(symbol "Oscillator_40MHz_YIC_OSC-S5_1_1"
				(rectangle
					(start 2.54 2.54)
					(end 16.51 -7.62)
					(stroke
						(width 0.254)
						(type default)
					)
					(fill
						(type background)
					)
				)
				(polyline
					(pts
						(xy 7.62 -1.27) (xy 8.255 -1.27) (xy 8.255 0) (xy 8.89 0) (xy 8.89 -1.27) (xy 9.525 -1.27) (xy 9.525 0)
						(xy 10.16 0) (xy 10.16 -1.27)
					)
					(stroke
						(width 0.254)
						(type default)
					)
					(fill
						(type background)
					)
				)
				(pin power_in line
					(at 0 0 0)
					(length 2.54)
					(name "VDD"
						(effects
							(font
								(size 1.27 1.27)
							)
						)
					)
					(number "4"
						(effects
							(font
								(size 1.27 1.27)
							)
						)
					)
				)
				(pin input line
					(at 0 -2.54 0)
					(length 2.54)
					(name "EN"
						(effects
							(font
								(size 1.27 1.27)
							)
						)
					)
					(number "1"
						(effects
							(font
								(size 1.27 1.27)
							)
						)
					)
				)
				(pin power_in line
					(at 0 -5.08 0)
					(length 2.54)
					(name "GND"
						(effects
							(font
								(size 1.27 1.27)
							)
						)
					)
					(number "2"
						(effects
							(font
								(size 1.27 1.27)
							)
						)
					)
				)
				(pin output line
					(at 19.05 0 180)
					(length 2.54)
					(name "OUT"
						(effects
							(font
								(size 1.27 1.27)
							)
						)
					)
					(number "3"
						(effects
							(font
								(size 1.27 1.27)
							)
						)
					)
				)
			)
		)
	(symbol "antmicroPMICPowerDistributionSwitchesLoadDrivers:DIO7553ST6"
			(exclude_from_sim no)
			(in_bom yes)
			(on_board yes)
			(property "Reference" "U"
				(at 31.75 -2.54 0)
				(effects
					(font
						(size 1.27 1.27)
						(thickness 0.15)
					)
					(justify left bottom)
				)
			)
			(property "Value" "DIO7553ST6"
				(at 31.75 -5.08 0)
				(effects
					(font
						(size 1.27 1.27)
						(thickness 0.15)
					)
					(justify left bottom)
					(hide yes)
				)
			)
			(property "Footprint" "antmicro-footprints:SOT-23-6"
				(at 31.75 -7.62 0)
				(effects
					(font
						(size 1.27 1.27)
						(thickness 0.15)
					)
					(justify left bottom)
					(hide yes)
				)
			)
			(property "Datasheet" "https://www.mouser.com/datasheet/2/802/7e5c577022fb784effcb3cdb25b437c0-1815562.pdf"
				(at 31.75 -10.16 0)
				(effects
					(font
						(size 1.27 1.27)
						(thickness 0.15)
					)
					(justify left bottom)
					(hide yes)
				)
			)
			(property "Description" "Power switch"
				(at 31.75 -22.86 0)
				(effects
					(font
						(size 1.27 1.27)
					)
					(justify left bottom)
					(hide yes)
				)
			)
			(property "MPN" "DIO7553ST6"
				(at 31.75 -12.7 0)
				(effects
					(font
						(size 1.27 1.27)
						(thickness 0.15)
					)
					(justify left bottom)
				)
			)
			(property "Manufacturer" "DIOO Microcircuits"
				(at 31.75 -15.24 0)
				(effects
					(font
						(size 1.27 1.27)
						(thickness 0.15)
					)
					(justify left bottom)
					(hide yes)
				)
			)
			(property "Author" "Antmicro"
				(at 31.75 -17.78 0)
				(effects
					(font
						(size 1.27 1.27)
						(thickness 0.15)
					)
					(justify left bottom)
					(hide yes)
				)
			)
			(property "License" "Apache-2.0"
				(at 31.75 -20.32 0)
				(effects
					(font
						(size 1.27 1.27)
						(thickness 0.15)
					)
					(justify left bottom)
					(hide yes)
				)
			)
			(property "ki_keywords" "SMT, PMIC, IC, POWER"
				(at 0 0 0)
				(effects
					(font
						(size 1.27 1.27)
					)
					(hide yes)
				)
			)
			(symbol "DIO7553ST6_1_1"
				(rectangle
					(start 2.54 2.54)
					(end 15.24 -8.89)
					(stroke
						(width 0.254)
						(type default)
					)
					(fill
						(type background)
					)
				)
				(pin power_in line
					(at 0 0 0)
					(length 2.54)
					(name "IN"
						(effects
							(font
								(size 1.27 1.27)
							)
						)
					)
					(number "1"
						(effects
							(font
								(size 1.27 1.27)
							)
						)
					)
				)
				(pin output line
					(at 0 -3.81 0)
					(length 2.54)
					(name "~{FAULT}"
						(effects
							(font
								(size 1.27 1.27)
							)
						)
					)
					(number "4"
						(effects
							(font
								(size 1.27 1.27)
							)
						)
					)
				)
				(pin input line
					(at 0 -6.35 0)
					(length 2.54)
					(name "EN"
						(effects
							(font
								(size 1.27 1.27)
							)
						)
					)
					(number "3"
						(effects
							(font
								(size 1.27 1.27)
							)
						)
					)
				)
				(pin power_out line
					(at 17.78 0 180)
					(length 2.54)
					(name "OUT"
						(effects
							(font
								(size 1.27 1.27)
							)
						)
					)
					(number "6"
						(effects
							(font
								(size 1.27 1.27)
							)
						)
					)
				)
				(pin passive line
					(at 17.78 -3.81 180)
					(length 2.54)
					(name "ILIM"
						(effects
							(font
								(size 1.27 1.27)
							)
						)
					)
					(number "5"
						(effects
							(font
								(size 1.27 1.27)
							)
						)
					)
				)
				(pin power_in line
					(at 17.78 -6.35 180)
					(length 2.54)
					(name "GND"
						(effects
							(font
								(size 1.27 1.27)
							)
						)
					)
					(number "2"
						(effects
							(font
								(size 1.27 1.27)
							)
						)
					)
				)
			)
		)
	(symbol "antmicroPMICVoltageRegulatorsLinear:AP7330-W5-7"
			(exclude_from_sim no)
			(in_bom yes)
			(on_board yes)
			(property "Reference" "U"
				(at 30.48 -5.08 0)
				(effects
					(font
						(size 1.27 1.27)
						(thickness 0.15)
					)
					(justify left bottom)
				)
			)
			(property "Value" "AP7330-W5-7"
				(at 30.48 -7.62 0)
				(effects
					(font
						(size 1.27 1.27)
						(thickness 0.15)
					)
					(justify left bottom)
					(hide yes)
				)
			)
			(property "Footprint" "antmicro-footprints:SOT-23-5"
				(at 30.48 -10.16 0)
				(effects
					(font
						(size 1.27 1.27)
						(thickness 0.15)
					)
					(justify left bottom)
					(hide yes)
				)
			)
			(property "Datasheet" "https://www.diodes.com/assets/Datasheets/AP7330.pdf"
				(at 30.48 -12.7 0)
				(effects
					(font
						(size 1.27 1.27)
						(thickness 0.15)
					)
					(justify left bottom)
					(hide yes)
				)
			)
			(property "Description" "Voltage regulator"
				(at 30.48 -25.4 0)
				(effects
					(font
						(size 1.27 1.27)
					)
					(justify left bottom)
					(hide yes)
				)
			)
			(property "MPN" "AP7330-W5-7"
				(at 30.48 -15.24 0)
				(effects
					(font
						(size 1.27 1.27)
						(thickness 0.15)
					)
					(justify left bottom)
				)
			)
			(property "Manufacturer" "Diodes Incorporated"
				(at 30.48 -17.78 0)
				(effects
					(font
						(size 1.27 1.27)
						(thickness 0.15)
					)
					(justify left bottom)
					(hide yes)
				)
			)
			(property "Author" "Antmicro"
				(at 30.48 -20.32 0)
				(effects
					(font
						(size 1.27 1.27)
						(thickness 0.15)
					)
					(justify left bottom)
					(hide yes)
				)
			)
			(property "License" "Apache-2.0"
				(at 30.48 -22.86 0)
				(effects
					(font
						(size 1.27 1.27)
						(thickness 0.15)
					)
					(justify left bottom)
					(hide yes)
				)
			)
			(property "ki_keywords" "SMT, PMIC, IC, VOLTAGE, LDO"
				(at 0 0 0)
				(effects
					(font
						(size 1.27 1.27)
					)
					(hide yes)
				)
			)
			(symbol "AP7330-W5-7_1_1"
				(rectangle
					(start 2.54 1.27)
					(end 12.7 -7.62)
					(stroke
						(width 0.254)
						(type default)
					)
					(fill
						(type background)
					)
				)
				(pin power_in line
					(at 0 0 0)
					(length 2.54)
					(name "V_{IN}"
						(effects
							(font
								(size 1.27 1.27)
							)
						)
					)
					(number "1"
						(effects
							(font
								(size 1.27 1.27)
							)
						)
					)
				)
				(pin input line
					(at 0 -5.08 0)
					(length 2.54)
					(name "EN"
						(effects
							(font
								(size 1.27 1.27)
							)
						)
					)
					(number "3"
						(effects
							(font
								(size 1.27 1.27)
							)
						)
					)
				)
				(pin power_in line
					(at 7.62 -10.16 90)
					(length 2.54)
					(name "GND"
						(effects
							(font
								(size 1.27 1.27)
							)
						)
					)
					(number "2"
						(effects
							(font
								(size 1.27 1.27)
							)
						)
					)
				)
				(pin power_out line
					(at 15.24 0 180)
					(length 2.54)
					(name "V_{OUT}"
						(effects
							(font
								(size 1.27 1.27)
							)
						)
					)
					(number "5"
						(effects
							(font
								(size 1.27 1.27)
							)
						)
					)
				)
				(pin passive line
					(at 15.24 -5.08 180)
					(length 2.54)
					(name "ADJ"
						(effects
							(font
								(size 1.27 1.27)
							)
						)
					)
					(number "4"
						(effects
							(font
								(size 1.27 1.27)
							)
						)
					)
				)
			)
		)
	(symbol "antmicroPMICVoltageRegulatorsLinear:MP20073DH"
			(exclude_from_sim no)
			(in_bom yes)
			(on_board yes)
			(property "Reference" "U"
				(at 35.56 -5.08 0)
				(effects
					(font
						(size 1.27 1.27)
						(thickness 0.15)
					)
					(justify left bottom)
				)
			)
			(property "Value" "MP20073DH"
				(at 35.56 -7.62 0)
				(effects
					(font
						(size 1.27 1.27)
						(thickness 0.15)
					)
					(justify left bottom)
					(hide yes)
				)
			)
			(property "Footprint" "antmicro-footprints:MSOP-8-1EP_3x3x1.1mm_P0.65mm"
				(at 35.56 -10.16 0)
				(effects
					(font
						(size 1.27 1.27)
						(thickness 0.15)
					)
					(justify left bottom)
					(hide yes)
				)
			)
			(property "Datasheet" "https://www.farnell.com/datasheets/2915039.pdf"
				(at 35.56 -12.7 0)
				(effects
					(font
						(size 1.27 1.27)
						(thickness 0.15)
					)
					(justify left bottom)
					(hide yes)
				)
			)
			(property "Description" "DDR Termination Regulator, DDR2, DDR3, 1.3V to 6V in, 2A, MSOP-EP-8"
				(at 35.56 -25.4 0)
				(effects
					(font
						(size 1.27 1.27)
					)
					(justify left bottom)
					(hide yes)
				)
			)
			(property "MPN" "MP20073DH-LF-P"
				(at 35.56 -15.24 0)
				(effects
					(font
						(size 1.27 1.27)
						(thickness 0.15)
					)
					(justify left bottom)
				)
			)
			(property "Manufacturer" "Monolithic Power Systems"
				(at 35.56 -17.78 0)
				(effects
					(font
						(size 1.27 1.27)
						(thickness 0.15)
					)
					(justify left bottom)
					(hide yes)
				)
			)
			(property "Author" "Antmicro"
				(at 35.56 -20.32 0)
				(effects
					(font
						(size 1.27 1.27)
						(thickness 0.15)
					)
					(justify left bottom)
					(hide yes)
				)
			)
			(property "License" "Apache-2.0"
				(at 35.56 -22.86 0)
				(effects
					(font
						(size 1.27 1.27)
						(thickness 0.15)
					)
					(justify left bottom)
					(hide yes)
				)
			)
			(property "ki_keywords" "SMT, PMIC, IC, DDR, MEMORY"
				(at 0 0 0)
				(effects
					(font
						(size 1.27 1.27)
					)
					(hide yes)
				)
			)
			(symbol "MP20073DH_1_1"
				(rectangle
					(start 2.54 2.54)
					(end 17.78 -17.78)
					(stroke
						(width 0.254)
						(type default)
					)
					(fill
						(type background)
					)
				)
				(pin power_in line
					(at 0 0 0)
					(length 2.54)
					(name "DDQ"
						(effects
							(font
								(size 1.27 1.27)
							)
						)
					)
					(number "1"
						(effects
							(font
								(size 1.27 1.27)
							)
						)
					)
				)
				(pin passive line
					(at 0 -2.54 0)
					(length 2.54)
					(name "REF"
						(effects
							(font
								(size 1.27 1.27)
							)
						)
					)
					(number "6"
						(effects
							(font
								(size 1.27 1.27)
							)
						)
					)
				)
				(pin passive line
					(at 0 -7.62 0)
					(length 2.54)
					(name "V_{DRV}"
						(effects
							(font
								(size 1.27 1.27)
							)
						)
					)
					(number "5"
						(effects
							(font
								(size 1.27 1.27)
							)
						)
					)
				)
				(pin passive line
					(at 0 -12.7 0)
					(length 2.54)
					(name "V_{TT_EN}"
						(effects
							(font
								(size 1.27 1.27)
							)
						)
					)
					(number "7"
						(effects
							(font
								(size 1.27 1.27)
							)
						)
					)
				)
				(pin power_in line
					(at 0 -15.24 0)
					(length 2.54)
					(name "GND"
						(effects
							(font
								(size 1.27 1.27)
							)
						)
					)
					(number "3"
						(effects
							(font
								(size 1.27 1.27)
							)
						)
					)
				)
				(pin passive line
					(at 0 -15.24 0)
					(length 2.54)
					(hide yes)
					(name "GND"
						(effects
							(font
								(size 1.27 1.27)
							)
						)
					)
					(number "9"
						(effects
							(font
								(size 1.27 1.27)
							)
						)
					)
				)
				(pin passive line
					(at 20.32 0 180)
					(length 2.54)
					(name "V_{TTSEN}"
						(effects
							(font
								(size 1.27 1.27)
							)
						)
					)
					(number "4"
						(effects
							(font
								(size 1.27 1.27)
							)
						)
					)
				)
				(pin passive line
					(at 20.32 -2.54 180)
					(length 2.54)
					(name "V_{TT}"
						(effects
							(font
								(size 1.27 1.27)
							)
						)
					)
					(number "2"
						(effects
							(font
								(size 1.27 1.27)
							)
						)
					)
				)
				(pin passive line
					(at 20.32 -12.7 180)
					(length 2.54)
					(name "V_{TTREF}"
						(effects
							(font
								(size 1.27 1.27)
							)
						)
					)
					(number "8"
						(effects
							(font
								(size 1.27 1.27)
							)
						)
					)
				)
			)
		)
	(symbol "antmicroPushbuttonSwitches:SW_B3U-3000PM_SMD"
			(pin_names
				(hide yes)
			)
			(exclude_from_sim no)
			(in_bom yes)
			(on_board yes)
			(property "Reference" "SW"
				(at 25.4 -2.54 0)
				(effects
					(font
						(size 1.27 1.27)
						(thickness 0.15)
					)
					(justify left bottom)
				)
			)
			(property "Value" "SW_B3U-3000PM_SMD"
				(at 25.4 -5.08 0)
				(effects
					(font
						(size 1.27 1.27)
						(thickness 0.15)
					)
					(justify left bottom)
					(hide yes)
				)
			)
			(property "Footprint" "antmicro-footprints:SW_B3U-3000PM_SMD"
				(at 25.4 -7.62 0)
				(effects
					(font
						(size 1.27 1.27)
						(thickness 0.15)
					)
					(justify left bottom)
					(hide yes)
				)
			)
			(property "Datasheet" "http://www.farnell.com/datasheets/2610940.pdf"
				(at 25.4 -10.16 0)
				(effects
					(font
						(size 1.27 1.27)
						(thickness 0.15)
					)
					(justify left bottom)
					(hide yes)
				)
			)
			(property "Description" "Tactile Switch SPST-NO Side Actuated Surface Mount, Right Angle"
				(at 25.4 -22.86 0)
				(effects
					(font
						(size 1.27 1.27)
					)
					(justify left bottom)
					(hide yes)
				)
			)
			(property "MPN" "B3U-3000PM"
				(at 25.4 -12.7 0)
				(effects
					(font
						(size 1.27 1.27)
						(thickness 0.15)
					)
					(justify left bottom)
				)
			)
			(property "Manufacturer" "Omron"
				(at 25.4 -15.24 0)
				(effects
					(font
						(size 1.27 1.27)
						(thickness 0.15)
					)
					(justify left bottom)
					(hide yes)
				)
			)
			(property "Author" "Antmicro"
				(at 25.4 -17.78 0)
				(effects
					(font
						(size 1.27 1.27)
						(thickness 0.15)
					)
					(justify left bottom)
					(hide yes)
				)
			)
			(property "License" "Apache-2.0"
				(at 25.4 -20.32 0)
				(effects
					(font
						(size 1.27 1.27)
						(thickness 0.15)
					)
					(justify left bottom)
					(hide yes)
				)
			)
			(property "ki_keywords" "HORIZONTAL, SMT, SWITCH, MECHANICAL, TACTILE"
				(at 0 0 0)
				(effects
					(font
						(size 1.27 1.27)
					)
					(hide yes)
				)
			)
			(symbol "SW_B3U-3000PM_SMD_1_1"
				(polyline
					(pts
						(xy 2.54 0) (xy 3.302 0)
					)
					(stroke
						(width 0.254)
						(type default)
					)
					(fill
						(type none)
					)
				)
				(polyline
					(pts
						(xy 3.302 1.27) (xy 6.858 1.27)
					)
					(stroke
						(width 0.254)
						(type default)
					)
					(fill
						(type none)
					)
				)
				(circle
					(center 3.556 0)
					(radius 0.254)
					(stroke
						(width 0.254)
						(type default)
					)
					(fill
						(type none)
					)
				)
				(polyline
					(pts
						(xy 4.064 2.794) (xy 6.096 2.794)
					)
					(stroke
						(width 0.254)
						(type default)
					)
					(fill
						(type none)
					)
				)
				(polyline
					(pts
						(xy 5.08 1.27) (xy 5.08 2.794)
					)
					(stroke
						(width 0.254)
						(type default)
					)
					(fill
						(type none)
					)
				)
				(circle
					(center 6.604 0)
					(radius 0.254)
					(stroke
						(width 0.254)
						(type default)
					)
					(fill
						(type none)
					)
				)
				(polyline
					(pts
						(xy 7.62 0) (xy 6.858 0)
					)
					(stroke
						(width 0.254)
						(type default)
					)
					(fill
						(type none)
					)
				)
				(pin passive line
					(at 0 0 0)
					(length 2.54)
					(name "1"
						(effects
							(font
								(size 1.27 1.27)
							)
						)
					)
					(number "1"
						(effects
							(font
								(size 1.27 1.27)
							)
						)
					)
				)
				(pin passive line
					(at 10.16 0 180)
					(length 2.54)
					(name "2"
						(effects
							(font
								(size 1.27 1.27)
							)
						)
					)
					(number "2"
						(effects
							(font
								(size 1.27 1.27)
							)
						)
					)
				)
			)
		)
	(symbol "antmicroResistorNetworksArrays:R_4x51R_0402_array"
			(pin_names
				(hide yes)
			)
			(exclude_from_sim no)
			(in_bom yes)
			(on_board yes)
			(property "Reference" "R"
				(at 26.67 -2.54 0)
				(effects
					(font
						(size 1.27 1.27)
						(thickness 0.15)
					)
					(justify left bottom)
				)
			)
			(property "Value" "R_4x51R_0402_array"
				(at 26.67 -5.08 0)
				(effects
					(font
						(size 1.27 1.27)
						(thickness 0.15)
					)
					(justify left bottom)
					(hide yes)
				)
			)
			(property "Footprint" "antmicro-footprints:R_Array_4x0402"
				(at 26.67 -10.16 0)
				(effects
					(font
						(size 1.27 1.27)
						(thickness 0.15)
					)
					(justify left bottom)
					(hide yes)
				)
			)
			(property "Datasheet" "http://industrial.panasonic.com/cdbs/www-data/pdf/AOC0000/AOC0000C14.pdf"
				(at 26.67 -12.7 0)
				(effects
					(font
						(size 1.27 1.27)
						(thickness 0.15)
					)
					(justify left bottom)
					(hide yes)
				)
			)
			(property "Description" "Fixed Network Resistor, 51 ohm, Isolated, 4 Resistors, 0804 [2010 Metric], Convex, ± 5%"
				(at 26.67 -25.4 0)
				(effects
					(font
						(size 1.27 1.27)
					)
					(justify left bottom)
					(hide yes)
				)
			)
			(property "MPN" "EXB28V510JX"
				(at 26.67 -15.24 0)
				(effects
					(font
						(size 1.27 1.27)
						(thickness 0.15)
					)
					(justify left bottom)
					(hide yes)
				)
			)
			(property "Manufacturer" "Panasonic"
				(at 26.67 -17.78 0)
				(effects
					(font
						(size 1.27 1.27)
						(thickness 0.15)
					)
					(justify left bottom)
					(hide yes)
				)
			)
			(property "Author" "Antmicro"
				(at 26.67 -20.32 0)
				(effects
					(font
						(size 1.27 1.27)
						(thickness 0.15)
					)
					(justify left bottom)
					(hide yes)
				)
			)
			(property "License" "Apache-2.0"
				(at 26.67 -22.86 0)
				(effects
					(font
						(size 1.27 1.27)
						(thickness 0.15)
					)
					(justify left bottom)
					(hide yes)
				)
			)
			(property "Val" "R_4x51R_0402"
				(at 26.67 -7.62 0)
				(effects
					(font
						(size 1.27 1.27)
					)
					(justify left bottom)
				)
			)
			(property "ki_keywords" "0402, SMT, RESISTOR, PASSIVE"
				(at 0 0 0)
				(effects
					(font
						(size 1.27 1.27)
					)
					(hide yes)
				)
			)
			(symbol "R_4x51R_0402_array_0_1"
				(polyline
					(pts
						(xy 2.54 0) (xy 3.175 0)
					)
					(stroke
						(width 0)
						(type default)
					)
					(fill
						(type none)
					)
				)
				(polyline
					(pts
						(xy 2.54 -2.54) (xy 3.175 -2.54)
					)
					(stroke
						(width 0)
						(type default)
					)
					(fill
						(type none)
					)
				)
				(polyline
					(pts
						(xy 2.54 -5.08) (xy 3.175 -5.08)
					)
					(stroke
						(width 0)
						(type default)
					)
					(fill
						(type none)
					)
				)
				(polyline
					(pts
						(xy 2.54 -7.62) (xy 3.175 -7.62)
					)
					(stroke
						(width 0)
						(type default)
					)
					(fill
						(type none)
					)
				)
				(rectangle
					(start 2.667 1.27)
					(end 7.493 -8.89)
					(stroke
						(width 0.254)
						(type default)
					)
					(fill
						(type background)
					)
				)
				(rectangle
					(start 6.985 0.635)
					(end 3.175 -0.635)
					(stroke
						(width 0.254)
						(type default)
					)
					(fill
						(type none)
					)
				)
				(polyline
					(pts
						(xy 6.985 0) (xy 7.62 0)
					)
					(stroke
						(width 0)
						(type default)
					)
					(fill
						(type none)
					)
				)
				(rectangle
					(start 6.985 -1.905)
					(end 3.175 -3.175)
					(stroke
						(width 0.254)
						(type default)
					)
					(fill
						(type none)
					)
				)
				(polyline
					(pts
						(xy 6.985 -2.54) (xy 7.62 -2.54)
					)
					(stroke
						(width 0)
						(type default)
					)
					(fill
						(type none)
					)
				)
				(rectangle
					(start 6.985 -4.445)
					(end 3.175 -5.715)
					(stroke
						(width 0.254)
						(type default)
					)
					(fill
						(type none)
					)
				)
				(polyline
					(pts
						(xy 6.985 -5.08) (xy 7.62 -5.08)
					)
					(stroke
						(width 0)
						(type default)
					)
					(fill
						(type none)
					)
				)
				(rectangle
					(start 6.985 -6.985)
					(end 3.175 -8.255)
					(stroke
						(width 0.254)
						(type default)
					)
					(fill
						(type none)
					)
				)
				(polyline
					(pts
						(xy 6.985 -7.62) (xy 7.62 -7.62)
					)
					(stroke
						(width 0)
						(type default)
					)
					(fill
						(type none)
					)
				)
			)
			(symbol "R_4x51R_0402_array_1_1"
				(pin passive line
					(at 0 0 0)
					(length 2.54)
					(name "R1.1"
						(effects
							(font
								(size 1.27 1.27)
							)
						)
					)
					(number "1"
						(effects
							(font
								(size 1.27 1.27)
							)
						)
					)
				)
				(pin passive line
					(at 0 -2.54 0)
					(length 2.54)
					(name "R2.1"
						(effects
							(font
								(size 1.27 1.27)
							)
						)
					)
					(number "2"
						(effects
							(font
								(size 1.27 1.27)
							)
						)
					)
				)
				(pin passive line
					(at 0 -5.08 0)
					(length 2.54)
					(name "R3.1"
						(effects
							(font
								(size 1.27 1.27)
							)
						)
					)
					(number "3"
						(effects
							(font
								(size 1.27 1.27)
							)
						)
					)
				)
				(pin passive line
					(at 0 -7.62 0)
					(length 2.54)
					(name "R4.1"
						(effects
							(font
								(size 1.27 1.27)
							)
						)
					)
					(number "4"
						(effects
							(font
								(size 1.27 1.27)
							)
						)
					)
				)
				(pin passive line
					(at 10.16 0 180)
					(length 2.54)
					(name "R1.2"
						(effects
							(font
								(size 1.27 1.27)
							)
						)
					)
					(number "8"
						(effects
							(font
								(size 1.27 1.27)
							)
						)
					)
				)
				(pin passive line
					(at 10.16 -2.54 180)
					(length 2.54)
					(name "R2.2"
						(effects
							(font
								(size 1.27 1.27)
							)
						)
					)
					(number "7"
						(effects
							(font
								(size 1.27 1.27)
							)
						)
					)
				)
				(pin passive line
					(at 10.16 -5.08 180)
					(length 2.54)
					(name "R3.2"
						(effects
							(font
								(size 1.27 1.27)
							)
						)
					)
					(number "6"
						(effects
							(font
								(size 1.27 1.27)
							)
						)
					)
				)
				(pin passive line
					(at 10.16 -7.62 180)
					(length 2.54)
					(name "R4.2"
						(effects
							(font
								(size 1.27 1.27)
							)
						)
					)
					(number "5"
						(effects
							(font
								(size 1.27 1.27)
							)
						)
					)
				)
			)
		)
	(symbol "antmicroResistors0402:R_0R_0402"
			(pin_numbers
				(hide yes)
			)
			(pin_names
				(hide yes)
			)
			(exclude_from_sim no)
			(in_bom yes)
			(on_board yes)
			(property "Reference" "R"
				(at 20.32 -5.08 0)
				(effects
					(font
						(size 1.27 1.27)
						(thickness 0.15)
					)
					(justify left bottom)
				)
			)
			(property "Value" "R_0R_0402"
				(at 20.32 -12.7 0)
				(effects
					(font
						(size 1.27 1.27)
						(thickness 0.15)
					)
					(justify left bottom)
					(hide yes)
				)
			)
			(property "Footprint" "antmicro-footprints:R_0402_1005Metric"
				(at 20.32 -15.24 0)
				(effects
					(font
						(size 1.27 1.27)
						(thickness 0.15)
					)
					(justify left bottom)
					(hide yes)
				)
			)
			(property "Datasheet" "https://industrial.panasonic.com/cdbs/www-data/pdf/RDA0000/AOA0000C301.pdf"
				(at 20.32 -17.78 0)
				(effects
					(font
						(size 1.27 1.27)
						(thickness 0.15)
					)
					(justify left bottom)
					(hide yes)
				)
			)
			(property "Description" "SMD Chip Resistor, Jumper, 0 ohm, 100 mW, 0402 [1005 Metric], Thick Film, General Purpose"
				(at 20.32 -33.02 0)
				(effects
					(font
						(size 1.27 1.27)
					)
					(justify left bottom)
					(hide yes)
				)
			)
			(property "MPN" "ERJ2GE0R00X"
				(at 20.32 -20.32 0)
				(effects
					(font
						(size 1.27 1.27)
						(thickness 0.15)
					)
					(justify left bottom)
					(hide yes)
				)
			)
			(property "Manufacturer" "Panasonic"
				(at 20.32 -22.86 0)
				(effects
					(font
						(size 1.27 1.27)
						(thickness 0.15)
					)
					(justify left bottom)
					(hide yes)
				)
			)
			(property "License" "Apache-2.0"
				(at 20.32 -25.4 0)
				(effects
					(font
						(size 1.27 1.27)
						(thickness 0.15)
					)
					(justify left bottom)
					(hide yes)
				)
			)
			(property "Author" "Antmicro"
				(at 20.32 -27.94 0)
				(effects
					(font
						(size 1.27 1.27)
						(thickness 0.15)
					)
					(justify left bottom)
					(hide yes)
				)
			)
			(property "Val" "0R"
				(at 20.32 -7.62 0)
				(effects
					(font
						(size 1.27 1.27)
						(thickness 0.15)
					)
					(justify left bottom)
				)
			)
			(property "Tolerance" "~"
				(at 20.32 -10.16 0)
				(effects
					(font
						(size 1.27 1.27)
					)
					(justify left bottom)
					(hide yes)
				)
			)
			(property "Current" "1A"
				(at 20.32 -30.48 0)
				(effects
					(font
						(size 1.27 1.27)
						(thickness 0.15)
					)
					(justify left bottom)
					(hide yes)
				)
			)
			(property "ki_keywords" "0402, SMT, RESISTOR, PASSIVE"
				(at 0 0 0)
				(effects
					(font
						(size 1.27 1.27)
					)
					(hide yes)
				)
			)
			(symbol "R_0R_0402_0_1"
				(rectangle
					(start 0.635 0.889)
					(end 4.445 -0.889)
					(stroke
						(width 0.254)
						(type default)
					)
					(fill
						(type none)
					)
				)
			)
			(symbol "R_0R_0402_1_1"
				(pin passive line
					(at 0 0 0)
					(length 0.635)
					(name "~"
						(effects
							(font
								(size 1.27 1.27)
							)
						)
					)
					(number "1"
						(effects
							(font
								(size 1.27 1.27)
							)
						)
					)
				)
				(pin passive line
					(at 5.08 0 180)
					(length 0.635)
					(name "~"
						(effects
							(font
								(size 1.27 1.27)
							)
						)
					)
					(number "2"
						(effects
							(font
								(size 1.27 1.27)
							)
						)
					)
				)
			)
		)
	(symbol "antmicroResistors0402:R_100R_0402"
			(pin_numbers
				(hide yes)
			)
			(pin_names
				(hide yes)
			)
			(exclude_from_sim no)
			(in_bom yes)
			(on_board yes)
			(property "Reference" "R"
				(at 20.32 -5.08 0)
				(effects
					(font
						(size 1.27 1.27)
						(thickness 0.15)
					)
					(justify left bottom)
				)
			)
			(property "Value" "R_100R_0402"
				(at 20.32 -12.7 0)
				(effects
					(font
						(size 1.27 1.27)
						(thickness 0.15)
					)
					(justify left bottom)
					(hide yes)
				)
			)
			(property "Footprint" "antmicro-footprints:R_0402_1005Metric"
				(at 20.32 -15.24 0)
				(effects
					(font
						(size 1.27 1.27)
						(thickness 0.15)
					)
					(justify left bottom)
					(hide yes)
				)
			)
			(property "Datasheet" "https://www.bourns.com/docs/product-datasheets/cr.pdf"
				(at 20.32 -17.78 0)
				(effects
					(font
						(size 1.27 1.27)
						(thickness 0.15)
					)
					(justify left bottom)
					(hide yes)
				)
			)
			(property "Description" "SMD Chip Resistor, 100 ohm, ± 1%, 62.5 mW, 0402 [1005 Metric], Thick Film, General Purpose"
				(at 20.32 -30.48 0)
				(effects
					(font
						(size 1.27 1.27)
					)
					(justify left bottom)
					(hide yes)
				)
			)
			(property "MPN" "CR0402-FX-1000GLF"
				(at 20.32 -20.32 0)
				(effects
					(font
						(size 1.27 1.27)
						(thickness 0.15)
					)
					(justify left bottom)
					(hide yes)
				)
			)
			(property "Manufacturer" "Bourns"
				(at 20.32 -22.86 0)
				(effects
					(font
						(size 1.27 1.27)
						(thickness 0.15)
					)
					(justify left bottom)
					(hide yes)
				)
			)
			(property "License" "Apache-2.0"
				(at 20.32 -25.4 0)
				(effects
					(font
						(size 1.27 1.27)
						(thickness 0.15)
					)
					(justify left bottom)
					(hide yes)
				)
			)
			(property "Author" "Antmicro"
				(at 20.32 -27.94 0)
				(effects
					(font
						(size 1.27 1.27)
						(thickness 0.15)
					)
					(justify left bottom)
					(hide yes)
				)
			)
			(property "Val" "100R"
				(at 20.32 -7.62 0)
				(effects
					(font
						(size 1.27 1.27)
						(thickness 0.15)
					)
					(justify left bottom)
				)
			)
			(property "Tolerance" "1%"
				(at 20.32 -10.16 0)
				(effects
					(font
						(size 1.27 1.27)
					)
					(justify left bottom)
					(hide yes)
				)
			)
			(property "ki_keywords" "0402, SMT, RESISTOR, PASSIVE"
				(at 0 0 0)
				(effects
					(font
						(size 1.27 1.27)
					)
					(hide yes)
				)
			)
			(symbol "R_100R_0402_0_1"
				(rectangle
					(start 0.635 0.889)
					(end 4.445 -0.889)
					(stroke
						(width 0.254)
						(type default)
					)
					(fill
						(type none)
					)
				)
			)
			(symbol "R_100R_0402_1_1"
				(pin passive line
					(at 0 0 0)
					(length 0.635)
					(name "~"
						(effects
							(font
								(size 1.27 1.27)
							)
						)
					)
					(number "1"
						(effects
							(font
								(size 1.27 1.27)
							)
						)
					)
				)
				(pin passive line
					(at 5.08 0 180)
					(length 0.635)
					(name "~"
						(effects
							(font
								(size 1.27 1.27)
							)
						)
					)
					(number "2"
						(effects
							(font
								(size 1.27 1.27)
							)
						)
					)
				)
			)
		)
	(symbol "antmicroResistors0402:R_100k_0402"
			(pin_numbers
				(hide yes)
			)
			(pin_names
				(hide yes)
			)
			(exclude_from_sim no)
			(in_bom yes)
			(on_board yes)
			(property "Reference" "R"
				(at 20.32 -5.08 0)
				(effects
					(font
						(size 1.27 1.27)
						(thickness 0.15)
					)
					(justify left bottom)
				)
			)
			(property "Value" "R_100k_0402"
				(at 20.32 -12.7 0)
				(effects
					(font
						(size 1.27 1.27)
						(thickness 0.15)
					)
					(justify left bottom)
					(hide yes)
				)
			)
			(property "Footprint" "antmicro-footprints:R_0402_1005Metric"
				(at 20.32 -15.24 0)
				(effects
					(font
						(size 1.27 1.27)
						(thickness 0.15)
					)
					(justify left bottom)
					(hide yes)
				)
			)
			(property "Datasheet" "https://www.bourns.com/docs/product-datasheets/cr.pdf"
				(at 20.32 -17.78 0)
				(effects
					(font
						(size 1.27 1.27)
						(thickness 0.15)
					)
					(justify left bottom)
					(hide yes)
				)
			)
			(property "Description" "SMD Chip Resistor, 100 kohm, ± 1%, 62.5 mW, 0402 [1005 Metric], Thick Film, General Purpose"
				(at 20.32 -30.48 0)
				(effects
					(font
						(size 1.27 1.27)
					)
					(justify left bottom)
					(hide yes)
				)
			)
			(property "MPN" "CR0402-FX-1003GLF"
				(at 20.32 -20.32 0)
				(effects
					(font
						(size 1.27 1.27)
						(thickness 0.15)
					)
					(justify left bottom)
					(hide yes)
				)
			)
			(property "Manufacturer" "Bourns"
				(at 20.32 -22.86 0)
				(effects
					(font
						(size 1.27 1.27)
						(thickness 0.15)
					)
					(justify left bottom)
					(hide yes)
				)
			)
			(property "License" "Apache-2.0"
				(at 20.32 -25.4 0)
				(effects
					(font
						(size 1.27 1.27)
						(thickness 0.15)
					)
					(justify left bottom)
					(hide yes)
				)
			)
			(property "Author" "Antmicro"
				(at 20.32 -27.94 0)
				(effects
					(font
						(size 1.27 1.27)
						(thickness 0.15)
					)
					(justify left bottom)
					(hide yes)
				)
			)
			(property "Val" "100k"
				(at 20.32 -7.62 0)
				(effects
					(font
						(size 1.27 1.27)
						(thickness 0.15)
					)
					(justify left bottom)
				)
			)
			(property "Tolerance" "1%"
				(at 20.32 -10.16 0)
				(effects
					(font
						(size 1.27 1.27)
					)
					(justify left bottom)
					(hide yes)
				)
			)
			(property "ki_keywords" "0402, SMT, RESISTOR, PASSIVE"
				(at 0 0 0)
				(effects
					(font
						(size 1.27 1.27)
					)
					(hide yes)
				)
			)
			(symbol "R_100k_0402_0_1"
				(rectangle
					(start 0.635 0.889)
					(end 4.445 -0.889)
					(stroke
						(width 0.254)
						(type default)
					)
					(fill
						(type none)
					)
				)
			)
			(symbol "R_100k_0402_1_1"
				(pin passive line
					(at 0 0 0)
					(length 0.635)
					(name "~"
						(effects
							(font
								(size 1.27 1.27)
							)
						)
					)
					(number "1"
						(effects
							(font
								(size 1.27 1.27)
							)
						)
					)
				)
				(pin passive line
					(at 5.08 0 180)
					(length 0.635)
					(name "~"
						(effects
							(font
								(size 1.27 1.27)
							)
						)
					)
					(number "2"
						(effects
							(font
								(size 1.27 1.27)
							)
						)
					)
				)
			)
		)
	(symbol "antmicroResistors0402:R_105R_0402"
			(pin_numbers
				(hide yes)
			)
			(pin_names
				(hide yes)
			)
			(exclude_from_sim no)
			(in_bom yes)
			(on_board yes)
			(property "Reference" "R"
				(at 20.32 -5.08 0)
				(effects
					(font
						(size 1.27 1.27)
						(thickness 0.15)
					)
					(justify left bottom)
				)
			)
			(property "Value" "R_105R_0402"
				(at 20.32 -12.7 0)
				(effects
					(font
						(size 1.27 1.27)
						(thickness 0.15)
					)
					(justify left bottom)
					(hide yes)
				)
			)
			(property "Footprint" "antmicro-footprints:R_0402_1005Metric"
				(at 20.32 -15.24 0)
				(effects
					(font
						(size 1.27 1.27)
						(thickness 0.15)
					)
					(justify left bottom)
					(hide yes)
				)
			)
			(property "Datasheet" "https://www.bourns.com/docs/product-datasheets/cr.pdf"
				(at 20.32 -17.78 0)
				(effects
					(font
						(size 1.27 1.27)
						(thickness 0.15)
					)
					(justify left bottom)
					(hide yes)
				)
			)
			(property "Description" "SMD Chip Resistor, 105 ohm, ± 1%, 62.5 mW, 0402 [1005 Metric], Thick Film, General Purpose"
				(at 20.32 -30.48 0)
				(effects
					(font
						(size 1.27 1.27)
					)
					(justify left bottom)
					(hide yes)
				)
			)
			(property "MPN" "CR0402-FX-1050GLF"
				(at 20.32 -20.32 0)
				(effects
					(font
						(size 1.27 1.27)
						(thickness 0.15)
					)
					(justify left bottom)
					(hide yes)
				)
			)
			(property "Manufacturer" "Bourns"
				(at 20.32 -22.86 0)
				(effects
					(font
						(size 1.27 1.27)
						(thickness 0.15)
					)
					(justify left bottom)
					(hide yes)
				)
			)
			(property "License" "Apache-2.0"
				(at 20.32 -25.4 0)
				(effects
					(font
						(size 1.27 1.27)
						(thickness 0.15)
					)
					(justify left bottom)
					(hide yes)
				)
			)
			(property "Author" "Antmicro"
				(at 20.32 -27.94 0)
				(effects
					(font
						(size 1.27 1.27)
						(thickness 0.15)
					)
					(justify left bottom)
					(hide yes)
				)
			)
			(property "Val" "105R"
				(at 20.32 -7.62 0)
				(effects
					(font
						(size 1.27 1.27)
						(thickness 0.15)
					)
					(justify left bottom)
				)
			)
			(property "Tolerance" "1%"
				(at 20.32 -10.16 0)
				(effects
					(font
						(size 1.27 1.27)
					)
					(justify left bottom)
					(hide yes)
				)
			)
			(property "ki_keywords" "0402, SMT, RESISTOR, PASSIVE"
				(at 0 0 0)
				(effects
					(font
						(size 1.27 1.27)
					)
					(hide yes)
				)
			)
			(symbol "R_105R_0402_0_1"
				(rectangle
					(start 0.635 0.889)
					(end 4.445 -0.889)
					(stroke
						(width 0.254)
						(type default)
					)
					(fill
						(type none)
					)
				)
			)
			(symbol "R_105R_0402_1_1"
				(pin passive line
					(at 0 0 0)
					(length 0.635)
					(name "~"
						(effects
							(font
								(size 1.27 1.27)
							)
						)
					)
					(number "1"
						(effects
							(font
								(size 1.27 1.27)
							)
						)
					)
				)
				(pin passive line
					(at 5.08 0 180)
					(length 0.635)
					(name "~"
						(effects
							(font
								(size 1.27 1.27)
							)
						)
					)
					(number "2"
						(effects
							(font
								(size 1.27 1.27)
							)
						)
					)
				)
			)
		)
	(symbol "antmicroResistors0402:R_10k_0402"
			(pin_numbers
				(hide yes)
			)
			(pin_names
				(hide yes)
			)
			(exclude_from_sim no)
			(in_bom yes)
			(on_board yes)
			(property "Reference" "R"
				(at 20.32 -5.08 0)
				(effects
					(font
						(size 1.27 1.27)
						(thickness 0.15)
					)
					(justify left bottom)
				)
			)
			(property "Value" "R_10k_0402"
				(at 20.32 -12.7 0)
				(effects
					(font
						(size 1.27 1.27)
						(thickness 0.15)
					)
					(justify left bottom)
					(hide yes)
				)
			)
			(property "Footprint" "antmicro-footprints:R_0402_1005Metric"
				(at 20.32 -15.24 0)
				(effects
					(font
						(size 1.27 1.27)
						(thickness 0.15)
					)
					(justify left bottom)
					(hide yes)
				)
			)
			(property "Datasheet" "https://www.bourns.com/docs/product-datasheets/cr.pdf"
				(at 20.32 -17.78 0)
				(effects
					(font
						(size 1.27 1.27)
						(thickness 0.15)
					)
					(justify left bottom)
					(hide yes)
				)
			)
			(property "Description" "SMD Chip Resistor, 10 kohm, ± 1%, 62.5 mW, 0402 [1005 Metric], Thick Film, General Purpose"
				(at 20.32 -30.48 0)
				(effects
					(font
						(size 1.27 1.27)
					)
					(justify left bottom)
					(hide yes)
				)
			)
			(property "MPN" "CR0402-FX-1002GLF"
				(at 20.32 -20.32 0)
				(effects
					(font
						(size 1.27 1.27)
						(thickness 0.15)
					)
					(justify left bottom)
					(hide yes)
				)
			)
			(property "Manufacturer" "Bourns"
				(at 20.32 -22.86 0)
				(effects
					(font
						(size 1.27 1.27)
						(thickness 0.15)
					)
					(justify left bottom)
					(hide yes)
				)
			)
			(property "License" "Apache-2.0"
				(at 20.32 -25.4 0)
				(effects
					(font
						(size 1.27 1.27)
						(thickness 0.15)
					)
					(justify left bottom)
					(hide yes)
				)
			)
			(property "Author" "Antmicro"
				(at 20.32 -27.94 0)
				(effects
					(font
						(size 1.27 1.27)
						(thickness 0.15)
					)
					(justify left bottom)
					(hide yes)
				)
			)
			(property "Val" "10k"
				(at 20.32 -7.62 0)
				(effects
					(font
						(size 1.27 1.27)
						(thickness 0.15)
					)
					(justify left bottom)
				)
			)
			(property "Tolerance" "1%"
				(at 20.32 -10.16 0)
				(effects
					(font
						(size 1.27 1.27)
					)
					(justify left bottom)
					(hide yes)
				)
			)
			(property "ki_keywords" "0402, SMT, RESISTOR, PASSIVE"
				(at 0 0 0)
				(effects
					(font
						(size 1.27 1.27)
					)
					(hide yes)
				)
			)
			(symbol "R_10k_0402_0_1"
				(rectangle
					(start 0.635 0.889)
					(end 4.445 -0.889)
					(stroke
						(width 0.254)
						(type default)
					)
					(fill
						(type none)
					)
				)
			)
			(symbol "R_10k_0402_1_1"
				(pin passive line
					(at 0 0 0)
					(length 0.635)
					(name "~"
						(effects
							(font
								(size 1.27 1.27)
							)
						)
					)
					(number "1"
						(effects
							(font
								(size 1.27 1.27)
							)
						)
					)
				)
				(pin passive line
					(at 5.08 0 180)
					(length 0.635)
					(name "~"
						(effects
							(font
								(size 1.27 1.27)
							)
						)
					)
					(number "2"
						(effects
							(font
								(size 1.27 1.27)
							)
						)
					)
				)
			)
		)
	(symbol "antmicroResistors0402:R_12k_0402"
			(pin_numbers
				(hide yes)
			)
			(pin_names
				(hide yes)
			)
			(exclude_from_sim no)
			(in_bom yes)
			(on_board yes)
			(property "Reference" "R"
				(at 20.32 -5.08 0)
				(effects
					(font
						(size 1.27 1.27)
						(thickness 0.15)
					)
					(justify left bottom)
				)
			)
			(property "Value" "R_12k_0402"
				(at 20.32 -12.7 0)
				(effects
					(font
						(size 1.27 1.27)
						(thickness 0.15)
					)
					(justify left bottom)
					(hide yes)
				)
			)
			(property "Footprint" "antmicro-footprints:R_0402_1005Metric"
				(at 20.32 -15.24 0)
				(effects
					(font
						(size 1.27 1.27)
						(thickness 0.15)
					)
					(justify left bottom)
					(hide yes)
				)
			)
			(property "Datasheet" "https://www.bourns.com/docs/product-datasheets/cr.pdf"
				(at 20.32 -17.78 0)
				(effects
					(font
						(size 1.27 1.27)
						(thickness 0.15)
					)
					(justify left bottom)
					(hide yes)
				)
			)
			(property "Description" "SMD Chip Resistor, 12 kohm, ± 1%, 62.5 mW, 0402 [1005 Metric], Thick Film, General Purpose"
				(at 20.32 -30.48 0)
				(effects
					(font
						(size 1.27 1.27)
					)
					(justify left bottom)
					(hide yes)
				)
			)
			(property "MPN" "CR0402-FX-1202GLF"
				(at 20.32 -20.32 0)
				(effects
					(font
						(size 1.27 1.27)
						(thickness 0.15)
					)
					(justify left bottom)
					(hide yes)
				)
			)
			(property "Manufacturer" "Bourns"
				(at 20.32 -22.86 0)
				(effects
					(font
						(size 1.27 1.27)
						(thickness 0.15)
					)
					(justify left bottom)
					(hide yes)
				)
			)
			(property "License" "Apache-2.0"
				(at 20.32 -25.4 0)
				(effects
					(font
						(size 1.27 1.27)
						(thickness 0.15)
					)
					(justify left bottom)
					(hide yes)
				)
			)
			(property "Author" "Antmicro"
				(at 20.32 -27.94 0)
				(effects
					(font
						(size 1.27 1.27)
						(thickness 0.15)
					)
					(justify left bottom)
					(hide yes)
				)
			)
			(property "Val" "12k"
				(at 20.32 -7.62 0)
				(effects
					(font
						(size 1.27 1.27)
						(thickness 0.15)
					)
					(justify left bottom)
				)
			)
			(property "Tolerance" "1%"
				(at 20.32 -10.16 0)
				(effects
					(font
						(size 1.27 1.27)
					)
					(justify left bottom)
					(hide yes)
				)
			)
			(property "ki_keywords" "0402, SMT, RESISTOR, PASSIVE"
				(at 0 0 0)
				(effects
					(font
						(size 1.27 1.27)
					)
					(hide yes)
				)
			)
			(symbol "R_12k_0402_0_1"
				(rectangle
					(start 0.635 0.889)
					(end 4.445 -0.889)
					(stroke
						(width 0.254)
						(type default)
					)
					(fill
						(type none)
					)
				)
			)
			(symbol "R_12k_0402_1_1"
				(pin passive line
					(at 0 0 0)
					(length 0.635)
					(name "~"
						(effects
							(font
								(size 1.27 1.27)
							)
						)
					)
					(number "1"
						(effects
							(font
								(size 1.27 1.27)
							)
						)
					)
				)
				(pin passive line
					(at 5.08 0 180)
					(length 0.635)
					(name "~"
						(effects
							(font
								(size 1.27 1.27)
							)
						)
					)
					(number "2"
						(effects
							(font
								(size 1.27 1.27)
							)
						)
					)
				)
			)
		)
	(symbol "antmicroResistors0402:R_15k_0402"
			(pin_numbers
				(hide yes)
			)
			(pin_names
				(hide yes)
			)
			(exclude_from_sim no)
			(in_bom yes)
			(on_board yes)
			(property "Reference" "R"
				(at 20.32 -5.08 0)
				(effects
					(font
						(size 1.27 1.27)
						(thickness 0.15)
					)
					(justify left bottom)
				)
			)
			(property "Value" "R_15k_0402"
				(at 20.32 -12.7 0)
				(effects
					(font
						(size 1.27 1.27)
						(thickness 0.15)
					)
					(justify left bottom)
					(hide yes)
				)
			)
			(property "Footprint" "antmicro-footprints:R_0402_1005Metric"
				(at 20.32 -15.24 0)
				(effects
					(font
						(size 1.27 1.27)
						(thickness 0.15)
					)
					(justify left bottom)
					(hide yes)
				)
			)
			(property "Datasheet" "https://www.bourns.com/docs/product-datasheets/cr.pdf"
				(at 20.32 -17.78 0)
				(effects
					(font
						(size 1.27 1.27)
						(thickness 0.15)
					)
					(justify left bottom)
					(hide yes)
				)
			)
			(property "Description" "SMD Chip Resistor, 15 kohm, ± 1%, 62.5 mW, 0402 [1005 Metric], Thick Film, General Purpose"
				(at 20.32 -30.48 0)
				(effects
					(font
						(size 1.27 1.27)
					)
					(justify left bottom)
					(hide yes)
				)
			)
			(property "MPN" "CR0402-FX-1502GLF"
				(at 20.32 -20.32 0)
				(effects
					(font
						(size 1.27 1.27)
						(thickness 0.15)
					)
					(justify left bottom)
					(hide yes)
				)
			)
			(property "Manufacturer" "Bourns"
				(at 20.32 -22.86 0)
				(effects
					(font
						(size 1.27 1.27)
						(thickness 0.15)
					)
					(justify left bottom)
					(hide yes)
				)
			)
			(property "License" "Apache-2.0"
				(at 20.32 -25.4 0)
				(effects
					(font
						(size 1.27 1.27)
						(thickness 0.15)
					)
					(justify left bottom)
					(hide yes)
				)
			)
			(property "Author" "Antmicro"
				(at 20.32 -27.94 0)
				(effects
					(font
						(size 1.27 1.27)
						(thickness 0.15)
					)
					(justify left bottom)
					(hide yes)
				)
			)
			(property "Val" "15k"
				(at 20.32 -7.62 0)
				(effects
					(font
						(size 1.27 1.27)
						(thickness 0.15)
					)
					(justify left bottom)
				)
			)
			(property "Tolerance" "1%"
				(at 20.32 -10.16 0)
				(effects
					(font
						(size 1.27 1.27)
					)
					(justify left bottom)
					(hide yes)
				)
			)
			(property "ki_keywords" "0402, SMT, RESISTOR, PASSIVE"
				(at 0 0 0)
				(effects
					(font
						(size 1.27 1.27)
					)
					(hide yes)
				)
			)
			(symbol "R_15k_0402_0_1"
				(rectangle
					(start 0.635 0.889)
					(end 4.445 -0.889)
					(stroke
						(width 0.254)
						(type default)
					)
					(fill
						(type none)
					)
				)
			)
			(symbol "R_15k_0402_1_1"
				(pin passive line
					(at 0 0 0)
					(length 0.635)
					(name "~"
						(effects
							(font
								(size 1.27 1.27)
							)
						)
					)
					(number "1"
						(effects
							(font
								(size 1.27 1.27)
							)
						)
					)
				)
				(pin passive line
					(at 5.08 0 180)
					(length 0.635)
					(name "~"
						(effects
							(font
								(size 1.27 1.27)
							)
						)
					)
					(number "2"
						(effects
							(font
								(size 1.27 1.27)
							)
						)
					)
				)
			)
		)
	(symbol "antmicroResistors0402:R_18k7_0402"
			(pin_numbers
				(hide yes)
			)
			(pin_names
				(hide yes)
			)
			(exclude_from_sim no)
			(in_bom yes)
			(on_board yes)
			(property "Reference" "R"
				(at 20.32 -5.08 0)
				(effects
					(font
						(size 1.27 1.27)
						(thickness 0.15)
					)
					(justify left bottom)
				)
			)
			(property "Value" "R_18k7_0402"
				(at 20.32 -12.7 0)
				(effects
					(font
						(size 1.27 1.27)
						(thickness 0.15)
					)
					(justify left bottom)
					(hide yes)
				)
			)
			(property "Footprint" "antmicro-footprints:R_0402_1005Metric"
				(at 20.32 -15.24 0)
				(effects
					(font
						(size 1.27 1.27)
						(thickness 0.15)
					)
					(justify left bottom)
					(hide yes)
				)
			)
			(property "Datasheet" "https://www.bourns.com/docs/product-datasheets/cr.pdf"
				(at 20.32 -17.78 0)
				(effects
					(font
						(size 1.27 1.27)
						(thickness 0.15)
					)
					(justify left bottom)
					(hide yes)
				)
			)
			(property "Description" "SMD Chip Resistor"
				(at 20.32 -30.48 0)
				(effects
					(font
						(size 1.27 1.27)
					)
					(justify left bottom)
					(hide yes)
				)
			)
			(property "MPN" "CR0402-FX-1872GLF"
				(at 20.32 -20.32 0)
				(effects
					(font
						(size 1.27 1.27)
						(thickness 0.15)
					)
					(justify left bottom)
					(hide yes)
				)
			)
			(property "Manufacturer" "Bourns"
				(at 20.32 -22.86 0)
				(effects
					(font
						(size 1.27 1.27)
						(thickness 0.15)
					)
					(justify left bottom)
					(hide yes)
				)
			)
			(property "License" "Apache-2.0"
				(at 20.32 -25.4 0)
				(effects
					(font
						(size 1.27 1.27)
						(thickness 0.15)
					)
					(justify left bottom)
					(hide yes)
				)
			)
			(property "Author" "Antmicro"
				(at 20.32 -27.94 0)
				(effects
					(font
						(size 1.27 1.27)
						(thickness 0.15)
					)
					(justify left bottom)
					(hide yes)
				)
			)
			(property "Val" "18k7"
				(at 20.32 -7.62 0)
				(effects
					(font
						(size 1.27 1.27)
						(thickness 0.15)
					)
					(justify left bottom)
				)
			)
			(property "Tolerance" "1%"
				(at 20.32 -10.16 0)
				(effects
					(font
						(size 1.27 1.27)
					)
					(justify left bottom)
					(hide yes)
				)
			)
			(property "ki_keywords" "0402, SMT, RESISTOR, PASSIVE"
				(at 0 0 0)
				(effects
					(font
						(size 1.27 1.27)
					)
					(hide yes)
				)
			)
			(symbol "R_18k7_0402_0_1"
				(rectangle
					(start 0.635 0.889)
					(end 4.445 -0.889)
					(stroke
						(width 0.254)
						(type default)
					)
					(fill
						(type none)
					)
				)
			)
			(symbol "R_18k7_0402_1_1"
				(pin passive line
					(at 0 0 0)
					(length 0.635)
					(name "~"
						(effects
							(font
								(size 1.27 1.27)
							)
						)
					)
					(number "1"
						(effects
							(font
								(size 1.27 1.27)
							)
						)
					)
				)
				(pin passive line
					(at 5.08 0 180)
					(length 0.635)
					(name "~"
						(effects
							(font
								(size 1.27 1.27)
							)
						)
					)
					(number "2"
						(effects
							(font
								(size 1.27 1.27)
							)
						)
					)
				)
			)
		)
	(symbol "antmicroResistors0402:R_1k3_0402"
			(pin_numbers
				(hide yes)
			)
			(pin_names
				(hide yes)
			)
			(exclude_from_sim no)
			(in_bom yes)
			(on_board yes)
			(property "Reference" "R"
				(at 20.32 -5.08 0)
				(effects
					(font
						(size 1.27 1.27)
						(thickness 0.15)
					)
					(justify left bottom)
				)
			)
			(property "Value" "R_1k3_0402"
				(at 20.32 -12.7 0)
				(effects
					(font
						(size 1.27 1.27)
						(thickness 0.15)
					)
					(justify left bottom)
					(hide yes)
				)
			)
			(property "Footprint" "antmicro-footprints:R_0402_1005Metric"
				(at 20.32 -15.24 0)
				(effects
					(font
						(size 1.27 1.27)
						(thickness 0.15)
					)
					(justify left bottom)
					(hide yes)
				)
			)
			(property "Datasheet" "https://www.bourns.com/docs/product-datasheets/cr.pdf"
				(at 20.32 -17.78 0)
				(effects
					(font
						(size 1.27 1.27)
						(thickness 0.15)
					)
					(justify left bottom)
					(hide yes)
				)
			)
			(property "Description" "SMD Chip Resistor, 1.3 kohm, ± 1%, 62.5 mW, 0402 [1005 Metric], Thick Film, General Purpose"
				(at 20.32 -30.48 0)
				(effects
					(font
						(size 1.27 1.27)
					)
					(justify left bottom)
					(hide yes)
				)
			)
			(property "MPN" "CR0402-FX-1301GLF"
				(at 20.32 -20.32 0)
				(effects
					(font
						(size 1.27 1.27)
						(thickness 0.15)
					)
					(justify left bottom)
					(hide yes)
				)
			)
			(property "Manufacturer" "Bourns"
				(at 20.32 -22.86 0)
				(effects
					(font
						(size 1.27 1.27)
						(thickness 0.15)
					)
					(justify left bottom)
					(hide yes)
				)
			)
			(property "License" "Apache-2.0"
				(at 20.32 -25.4 0)
				(effects
					(font
						(size 1.27 1.27)
						(thickness 0.15)
					)
					(justify left bottom)
					(hide yes)
				)
			)
			(property "Author" "Antmicro"
				(at 20.32 -27.94 0)
				(effects
					(font
						(size 1.27 1.27)
						(thickness 0.15)
					)
					(justify left bottom)
					(hide yes)
				)
			)
			(property "Val" "1k3"
				(at 20.32 -7.62 0)
				(effects
					(font
						(size 1.27 1.27)
						(thickness 0.15)
					)
					(justify left bottom)
				)
			)
			(property "Tolerance" "1%"
				(at 20.32 -10.16 0)
				(effects
					(font
						(size 1.27 1.27)
					)
					(justify left bottom)
					(hide yes)
				)
			)
			(property "ki_keywords" "0402, SMT, RESISTOR, PASSIVE"
				(at 0 0 0)
				(effects
					(font
						(size 1.27 1.27)
					)
					(hide yes)
				)
			)
			(symbol "R_1k3_0402_0_1"
				(rectangle
					(start 0.635 0.889)
					(end 4.445 -0.889)
					(stroke
						(width 0.254)
						(type default)
					)
					(fill
						(type none)
					)
				)
			)
			(symbol "R_1k3_0402_1_1"
				(pin passive line
					(at 0 0 0)
					(length 0.635)
					(name "~"
						(effects
							(font
								(size 1.27 1.27)
							)
						)
					)
					(number "1"
						(effects
							(font
								(size 1.27 1.27)
							)
						)
					)
				)
				(pin passive line
					(at 5.08 0 180)
					(length 0.635)
					(name "~"
						(effects
							(font
								(size 1.27 1.27)
							)
						)
					)
					(number "2"
						(effects
							(font
								(size 1.27 1.27)
							)
						)
					)
				)
			)
		)
	(symbol "antmicroResistors0402:R_1k5_0402"
			(pin_numbers
				(hide yes)
			)
			(pin_names
				(hide yes)
			)
			(exclude_from_sim no)
			(in_bom yes)
			(on_board yes)
			(property "Reference" "R"
				(at 20.32 -5.08 0)
				(effects
					(font
						(size 1.27 1.27)
						(thickness 0.15)
					)
					(justify left bottom)
				)
			)
			(property "Value" "R_1k5_0402"
				(at 20.32 -12.7 0)
				(effects
					(font
						(size 1.27 1.27)
						(thickness 0.15)
					)
					(justify left bottom)
					(hide yes)
				)
			)
			(property "Footprint" "antmicro-footprints:R_0402_1005Metric"
				(at 20.32 -15.24 0)
				(effects
					(font
						(size 1.27 1.27)
						(thickness 0.15)
					)
					(justify left bottom)
					(hide yes)
				)
			)
			(property "Datasheet" "https://www.bourns.com/docs/product-datasheets/cr.pdf"
				(at 20.32 -17.78 0)
				(effects
					(font
						(size 1.27 1.27)
						(thickness 0.15)
					)
					(justify left bottom)
					(hide yes)
				)
			)
			(property "Description" "SMD Chip Resistor, 1.5 kohm, ± 1%, 62.5 mW, 0402 [1005 Metric], Thick Film, General Purpose"
				(at 20.32 -30.48 0)
				(effects
					(font
						(size 1.27 1.27)
					)
					(justify left bottom)
					(hide yes)
				)
			)
			(property "MPN" "CR0402-FX-1501GLF"
				(at 20.32 -20.32 0)
				(effects
					(font
						(size 1.27 1.27)
						(thickness 0.15)
					)
					(justify left bottom)
					(hide yes)
				)
			)
			(property "Manufacturer" "Bourns"
				(at 20.32 -22.86 0)
				(effects
					(font
						(size 1.27 1.27)
						(thickness 0.15)
					)
					(justify left bottom)
					(hide yes)
				)
			)
			(property "License" "Apache-2.0"
				(at 20.32 -25.4 0)
				(effects
					(font
						(size 1.27 1.27)
						(thickness 0.15)
					)
					(justify left bottom)
					(hide yes)
				)
			)
			(property "Author" "Antmicro"
				(at 20.32 -27.94 0)
				(effects
					(font
						(size 1.27 1.27)
						(thickness 0.15)
					)
					(justify left bottom)
					(hide yes)
				)
			)
			(property "Val" "1k5"
				(at 20.32 -7.62 0)
				(effects
					(font
						(size 1.27 1.27)
						(thickness 0.15)
					)
					(justify left bottom)
				)
			)
			(property "Tolerance" "1%"
				(at 20.32 -10.16 0)
				(effects
					(font
						(size 1.27 1.27)
					)
					(justify left bottom)
					(hide yes)
				)
			)
			(property "ki_keywords" "0402, SMT, RESISTOR, PASSIVE"
				(at 0 0 0)
				(effects
					(font
						(size 1.27 1.27)
					)
					(hide yes)
				)
			)
			(symbol "R_1k5_0402_0_1"
				(rectangle
					(start 0.635 0.889)
					(end 4.445 -0.889)
					(stroke
						(width 0.254)
						(type default)
					)
					(fill
						(type none)
					)
				)
			)
			(symbol "R_1k5_0402_1_1"
				(pin passive line
					(at 0 0 0)
					(length 0.635)
					(name "~"
						(effects
							(font
								(size 1.27 1.27)
							)
						)
					)
					(number "1"
						(effects
							(font
								(size 1.27 1.27)
							)
						)
					)
				)
				(pin passive line
					(at 5.08 0 180)
					(length 0.635)
					(name "~"
						(effects
							(font
								(size 1.27 1.27)
							)
						)
					)
					(number "2"
						(effects
							(font
								(size 1.27 1.27)
							)
						)
					)
				)
			)
		)
	(symbol "antmicroResistors0402:R_1k_0402"
			(pin_numbers
				(hide yes)
			)
			(pin_names
				(hide yes)
			)
			(exclude_from_sim no)
			(in_bom yes)
			(on_board yes)
			(property "Reference" "R"
				(at 20.32 -5.08 0)
				(effects
					(font
						(size 1.27 1.27)
						(thickness 0.15)
					)
					(justify left bottom)
				)
			)
			(property "Value" "R_1k_0402"
				(at 20.32 -12.7 0)
				(effects
					(font
						(size 1.27 1.27)
						(thickness 0.15)
					)
					(justify left bottom)
					(hide yes)
				)
			)
			(property "Footprint" "antmicro-footprints:R_0402_1005Metric"
				(at 20.32 -15.24 0)
				(effects
					(font
						(size 1.27 1.27)
						(thickness 0.15)
					)
					(justify left bottom)
					(hide yes)
				)
			)
			(property "Datasheet" "https://www.bourns.com/docs/product-datasheets/cr.pdf"
				(at 20.32 -17.78 0)
				(effects
					(font
						(size 1.27 1.27)
						(thickness 0.15)
					)
					(justify left bottom)
					(hide yes)
				)
			)
			(property "Description" "SMD Chip Resistor, 1 kohm, ± 1%, 63 mW, 0402 [1005 Metric], Thick Film, General Purpose"
				(at 20.32 -30.48 0)
				(effects
					(font
						(size 1.27 1.27)
					)
					(justify left bottom)
					(hide yes)
				)
			)
			(property "MPN" "CR0402-FX-1001GLF"
				(at 20.32 -20.32 0)
				(effects
					(font
						(size 1.27 1.27)
						(thickness 0.15)
					)
					(justify left bottom)
					(hide yes)
				)
			)
			(property "Manufacturer" "Bourns"
				(at 20.32 -22.86 0)
				(effects
					(font
						(size 1.27 1.27)
						(thickness 0.15)
					)
					(justify left bottom)
					(hide yes)
				)
			)
			(property "License" "Apache-2.0"
				(at 20.32 -25.4 0)
				(effects
					(font
						(size 1.27 1.27)
						(thickness 0.15)
					)
					(justify left bottom)
					(hide yes)
				)
			)
			(property "Author" "Antmicro"
				(at 20.32 -27.94 0)
				(effects
					(font
						(size 1.27 1.27)
						(thickness 0.15)
					)
					(justify left bottom)
					(hide yes)
				)
			)
			(property "Val" "1k"
				(at 20.32 -7.62 0)
				(effects
					(font
						(size 1.27 1.27)
						(thickness 0.15)
					)
					(justify left bottom)
				)
			)
			(property "Tolerance" "1%"
				(at 20.32 -10.16 0)
				(effects
					(font
						(size 1.27 1.27)
					)
					(justify left bottom)
					(hide yes)
				)
			)
			(property "ki_keywords" "0402, SMT, RESISTOR, PASSIVE"
				(at 0 0 0)
				(effects
					(font
						(size 1.27 1.27)
					)
					(hide yes)
				)
			)
			(symbol "R_1k_0402_0_1"
				(rectangle
					(start 0.635 0.889)
					(end 4.445 -0.889)
					(stroke
						(width 0.254)
						(type default)
					)
					(fill
						(type none)
					)
				)
			)
			(symbol "R_1k_0402_1_1"
				(pin passive line
					(at 0 0 0)
					(length 0.635)
					(name "~"
						(effects
							(font
								(size 1.27 1.27)
							)
						)
					)
					(number "1"
						(effects
							(font
								(size 1.27 1.27)
							)
						)
					)
				)
				(pin passive line
					(at 5.08 0 180)
					(length 0.635)
					(name "~"
						(effects
							(font
								(size 1.27 1.27)
							)
						)
					)
					(number "2"
						(effects
							(font
								(size 1.27 1.27)
							)
						)
					)
				)
			)
		)
	(symbol "antmicroResistors0402:R_22R_0402"
			(pin_numbers
				(hide yes)
			)
			(pin_names
				(hide yes)
			)
			(exclude_from_sim no)
			(in_bom yes)
			(on_board yes)
			(property "Reference" "R"
				(at 20.32 -5.08 0)
				(effects
					(font
						(size 1.27 1.27)
						(thickness 0.15)
					)
					(justify left bottom)
				)
			)
			(property "Value" "R_22R_0402"
				(at 20.32 -12.7 0)
				(effects
					(font
						(size 1.27 1.27)
						(thickness 0.15)
					)
					(justify left bottom)
					(hide yes)
				)
			)
			(property "Footprint" "antmicro-footprints:R_0402_1005Metric"
				(at 20.32 -15.24 0)
				(effects
					(font
						(size 1.27 1.27)
						(thickness 0.15)
					)
					(justify left bottom)
					(hide yes)
				)
			)
			(property "Datasheet" "https://www.bourns.com/docs/product-datasheets/cr.pdf"
				(at 20.32 -17.78 0)
				(effects
					(font
						(size 1.27 1.27)
						(thickness 0.15)
					)
					(justify left bottom)
					(hide yes)
				)
			)
			(property "Description" "SMD Chip Resistor, 22 ohm, ± 1%, 62.5 mW, 0402 [1005 Metric], Thick Film, General Purpose"
				(at 20.32 -30.48 0)
				(effects
					(font
						(size 1.27 1.27)
					)
					(justify left bottom)
					(hide yes)
				)
			)
			(property "MPN" "CR0402-FX-22R0GLF"
				(at 20.32 -20.32 0)
				(effects
					(font
						(size 1.27 1.27)
						(thickness 0.15)
					)
					(justify left bottom)
					(hide yes)
				)
			)
			(property "Manufacturer" "Bourns"
				(at 20.32 -22.86 0)
				(effects
					(font
						(size 1.27 1.27)
						(thickness 0.15)
					)
					(justify left bottom)
					(hide yes)
				)
			)
			(property "License" "Apache-2.0"
				(at 20.32 -25.4 0)
				(effects
					(font
						(size 1.27 1.27)
						(thickness 0.15)
					)
					(justify left bottom)
					(hide yes)
				)
			)
			(property "Author" "Antmicro"
				(at 20.32 -27.94 0)
				(effects
					(font
						(size 1.27 1.27)
						(thickness 0.15)
					)
					(justify left bottom)
					(hide yes)
				)
			)
			(property "Val" "22R"
				(at 20.32 -7.62 0)
				(effects
					(font
						(size 1.27 1.27)
						(thickness 0.15)
					)
					(justify left bottom)
				)
			)
			(property "Tolerance" "1%"
				(at 20.32 -10.16 0)
				(effects
					(font
						(size 1.27 1.27)
					)
					(justify left bottom)
					(hide yes)
				)
			)
			(property "ki_keywords" "0402, SMT, RESISTOR, PASSIVE"
				(at 0 0 0)
				(effects
					(font
						(size 1.27 1.27)
					)
					(hide yes)
				)
			)
			(symbol "R_22R_0402_0_1"
				(rectangle
					(start 0.635 0.889)
					(end 4.445 -0.889)
					(stroke
						(width 0.254)
						(type default)
					)
					(fill
						(type none)
					)
				)
			)
			(symbol "R_22R_0402_1_1"
				(pin passive line
					(at 0 0 0)
					(length 0.635)
					(name "~"
						(effects
							(font
								(size 1.27 1.27)
							)
						)
					)
					(number "1"
						(effects
							(font
								(size 1.27 1.27)
							)
						)
					)
				)
				(pin passive line
					(at 5.08 0 180)
					(length 0.635)
					(name "~"
						(effects
							(font
								(size 1.27 1.27)
							)
						)
					)
					(number "2"
						(effects
							(font
								(size 1.27 1.27)
							)
						)
					)
				)
			)
		)
	(symbol "antmicroResistors0402:R_240R_0402"
			(pin_numbers
				(hide yes)
			)
			(pin_names
				(hide yes)
			)
			(exclude_from_sim no)
			(in_bom yes)
			(on_board yes)
			(property "Reference" "R"
				(at 20.32 -5.08 0)
				(effects
					(font
						(size 1.27 1.27)
						(thickness 0.15)
					)
					(justify left bottom)
				)
			)
			(property "Value" "R_240R_0402"
				(at 20.32 -12.7 0)
				(effects
					(font
						(size 1.27 1.27)
						(thickness 0.15)
					)
					(justify left bottom)
					(hide yes)
				)
			)
			(property "Footprint" "antmicro-footprints:R_0402_1005Metric"
				(at 20.32 -15.24 0)
				(effects
					(font
						(size 1.27 1.27)
						(thickness 0.15)
					)
					(justify left bottom)
					(hide yes)
				)
			)
			(property "Datasheet" "https://www.bourns.com/docs/product-datasheets/cr.pdf"
				(at 20.32 -17.78 0)
				(effects
					(font
						(size 1.27 1.27)
						(thickness 0.15)
					)
					(justify left bottom)
					(hide yes)
				)
			)
			(property "Description" "SMD Chip Resistor, 240 ohm, ± 1%, 63 mW, 0402 [1005 Metric], Thick Film, General Purpose"
				(at 20.32 -30.48 0)
				(effects
					(font
						(size 1.27 1.27)
					)
					(justify left bottom)
					(hide yes)
				)
			)
			(property "MPN" "CR0402-FX-2400GLF"
				(at 20.32 -20.32 0)
				(effects
					(font
						(size 1.27 1.27)
						(thickness 0.15)
					)
					(justify left bottom)
					(hide yes)
				)
			)
			(property "Manufacturer" "Bourns"
				(at 20.32 -22.86 0)
				(effects
					(font
						(size 1.27 1.27)
						(thickness 0.15)
					)
					(justify left bottom)
					(hide yes)
				)
			)
			(property "License" "Apache-2.0"
				(at 20.32 -25.4 0)
				(effects
					(font
						(size 1.27 1.27)
						(thickness 0.15)
					)
					(justify left bottom)
					(hide yes)
				)
			)
			(property "Author" "Antmicro"
				(at 20.32 -27.94 0)
				(effects
					(font
						(size 1.27 1.27)
						(thickness 0.15)
					)
					(justify left bottom)
					(hide yes)
				)
			)
			(property "Val" "240R"
				(at 20.32 -7.62 0)
				(effects
					(font
						(size 1.27 1.27)
						(thickness 0.15)
					)
					(justify left bottom)
				)
			)
			(property "Tolerance" "1%"
				(at 20.32 -10.16 0)
				(effects
					(font
						(size 1.27 1.27)
					)
					(justify left bottom)
					(hide yes)
				)
			)
			(property "ki_keywords" "0402, SMT, RESISTOR, PASSIVE"
				(at 0 0 0)
				(effects
					(font
						(size 1.27 1.27)
					)
					(hide yes)
				)
			)
			(symbol "R_240R_0402_0_1"
				(rectangle
					(start 0.635 0.889)
					(end 4.445 -0.889)
					(stroke
						(width 0.254)
						(type default)
					)
					(fill
						(type none)
					)
				)
			)
			(symbol "R_240R_0402_1_1"
				(pin passive line
					(at 0 0 0)
					(length 0.635)
					(name "~"
						(effects
							(font
								(size 1.27 1.27)
							)
						)
					)
					(number "1"
						(effects
							(font
								(size 1.27 1.27)
							)
						)
					)
				)
				(pin passive line
					(at 5.08 0 180)
					(length 0.635)
					(name "~"
						(effects
							(font
								(size 1.27 1.27)
							)
						)
					)
					(number "2"
						(effects
							(font
								(size 1.27 1.27)
							)
						)
					)
				)
			)
		)
	(symbol "antmicroResistors0402:R_24k_0402"
			(pin_numbers
				(hide yes)
			)
			(pin_names
				(hide yes)
			)
			(exclude_from_sim no)
			(in_bom yes)
			(on_board yes)
			(property "Reference" "R"
				(at 20.32 -5.08 0)
				(effects
					(font
						(size 1.27 1.27)
						(thickness 0.15)
					)
					(justify left bottom)
				)
			)
			(property "Value" "R_24k_0402"
				(at 20.32 -12.7 0)
				(effects
					(font
						(size 1.27 1.27)
						(thickness 0.15)
					)
					(justify left bottom)
					(hide yes)
				)
			)
			(property "Footprint" "antmicro-footprints:R_0402_1005Metric"
				(at 20.32 -15.24 0)
				(effects
					(font
						(size 1.27 1.27)
						(thickness 0.15)
					)
					(justify left bottom)
					(hide yes)
				)
			)
			(property "Datasheet" "https://www.bourns.com/docs/product-datasheets/cr.pdf"
				(at 20.32 -17.78 0)
				(effects
					(font
						(size 1.27 1.27)
						(thickness 0.15)
					)
					(justify left bottom)
					(hide yes)
				)
			)
			(property "Description" "SMD Chip Resistor, 24 kohm, ± 1%, 100 mW, 0402 [1005 Metric], Thick Film, Precision"
				(at 20.32 -30.48 0)
				(effects
					(font
						(size 1.27 1.27)
					)
					(justify left bottom)
					(hide yes)
				)
			)
			(property "MPN" "CR0402-FX-2402GLF"
				(at 20.32 -20.32 0)
				(effects
					(font
						(size 1.27 1.27)
						(thickness 0.15)
					)
					(justify left bottom)
					(hide yes)
				)
			)
			(property "Manufacturer" "Bourns"
				(at 20.32 -22.86 0)
				(effects
					(font
						(size 1.27 1.27)
						(thickness 0.15)
					)
					(justify left bottom)
					(hide yes)
				)
			)
			(property "License" "Apache-2.0"
				(at 20.32 -25.4 0)
				(effects
					(font
						(size 1.27 1.27)
						(thickness 0.15)
					)
					(justify left bottom)
					(hide yes)
				)
			)
			(property "Author" "Antmicro"
				(at 20.32 -27.94 0)
				(effects
					(font
						(size 1.27 1.27)
						(thickness 0.15)
					)
					(justify left bottom)
					(hide yes)
				)
			)
			(property "Val" "24k"
				(at 20.32 -7.62 0)
				(effects
					(font
						(size 1.27 1.27)
						(thickness 0.15)
					)
					(justify left bottom)
				)
			)
			(property "Tolerance" "1%"
				(at 20.32 -10.16 0)
				(effects
					(font
						(size 1.27 1.27)
					)
					(justify left bottom)
					(hide yes)
				)
			)
			(property "ki_keywords" "0402, SMT, RESISTOR, PASSIVE"
				(at 0 0 0)
				(effects
					(font
						(size 1.27 1.27)
					)
					(hide yes)
				)
			)
			(symbol "R_24k_0402_0_1"
				(rectangle
					(start 0.635 0.889)
					(end 4.445 -0.889)
					(stroke
						(width 0.254)
						(type default)
					)
					(fill
						(type none)
					)
				)
			)
			(symbol "R_24k_0402_1_1"
				(pin passive line
					(at 0 0 0)
					(length 0.635)
					(name "~"
						(effects
							(font
								(size 1.27 1.27)
							)
						)
					)
					(number "1"
						(effects
							(font
								(size 1.27 1.27)
							)
						)
					)
				)
				(pin passive line
					(at 5.08 0 180)
					(length 0.635)
					(name "~"
						(effects
							(font
								(size 1.27 1.27)
							)
						)
					)
					(number "2"
						(effects
							(font
								(size 1.27 1.27)
							)
						)
					)
				)
			)
		)
	(symbol "antmicroResistors0402:R_27R_0402"
			(pin_numbers
				(hide yes)
			)
			(pin_names
				(hide yes)
			)
			(exclude_from_sim no)
			(in_bom yes)
			(on_board yes)
			(property "Reference" "R"
				(at 20.32 -5.08 0)
				(effects
					(font
						(size 1.27 1.27)
						(thickness 0.15)
					)
					(justify left bottom)
				)
			)
			(property "Value" "R_27R_0402"
				(at 20.32 -12.7 0)
				(effects
					(font
						(size 1.27 1.27)
						(thickness 0.15)
					)
					(justify left bottom)
					(hide yes)
				)
			)
			(property "Footprint" "antmicro-footprints:R_0402_1005Metric"
				(at 20.32 -15.24 0)
				(effects
					(font
						(size 1.27 1.27)
						(thickness 0.15)
					)
					(justify left bottom)
					(hide yes)
				)
			)
			(property "Datasheet" "https://www.bourns.com/docs/product-datasheets/cr.pdf"
				(at 20.32 -17.78 0)
				(effects
					(font
						(size 1.27 1.27)
						(thickness 0.15)
					)
					(justify left bottom)
					(hide yes)
				)
			)
			(property "Description" "SMD Chip Resistor, 27 ohm, ± 1%, 63 mW, 0402 [1005 Metric], Thick Film, General Purpose"
				(at 20.32 -30.48 0)
				(effects
					(font
						(size 1.27 1.27)
					)
					(justify left bottom)
					(hide yes)
				)
			)
			(property "MPN" "CR0402-FX-27R0GLF"
				(at 20.32 -20.32 0)
				(effects
					(font
						(size 1.27 1.27)
						(thickness 0.15)
					)
					(justify left bottom)
					(hide yes)
				)
			)
			(property "Manufacturer" "Bourns"
				(at 20.32 -22.86 0)
				(effects
					(font
						(size 1.27 1.27)
						(thickness 0.15)
					)
					(justify left bottom)
					(hide yes)
				)
			)
			(property "License" "Apache-2.0"
				(at 20.32 -25.4 0)
				(effects
					(font
						(size 1.27 1.27)
						(thickness 0.15)
					)
					(justify left bottom)
					(hide yes)
				)
			)
			(property "Author" "Antmicro"
				(at 20.32 -27.94 0)
				(effects
					(font
						(size 1.27 1.27)
						(thickness 0.15)
					)
					(justify left bottom)
					(hide yes)
				)
			)
			(property "Val" "27R"
				(at 20.32 -7.62 0)
				(effects
					(font
						(size 1.27 1.27)
						(thickness 0.15)
					)
					(justify left bottom)
				)
			)
			(property "Tolerance" "1%"
				(at 20.32 -10.16 0)
				(effects
					(font
						(size 1.27 1.27)
					)
					(justify left bottom)
					(hide yes)
				)
			)
			(property "ki_keywords" "0402, SMT, RESISTOR, PASSIVE"
				(at 0 0 0)
				(effects
					(font
						(size 1.27 1.27)
					)
					(hide yes)
				)
			)
			(symbol "R_27R_0402_0_1"
				(rectangle
					(start 0.635 0.889)
					(end 4.445 -0.889)
					(stroke
						(width 0.254)
						(type default)
					)
					(fill
						(type none)
					)
				)
			)
			(symbol "R_27R_0402_1_1"
				(pin passive line
					(at 0 0 0)
					(length 0.635)
					(name "~"
						(effects
							(font
								(size 1.27 1.27)
							)
						)
					)
					(number "1"
						(effects
							(font
								(size 1.27 1.27)
							)
						)
					)
				)
				(pin passive line
					(at 5.08 0 180)
					(length 0.635)
					(name "~"
						(effects
							(font
								(size 1.27 1.27)
							)
						)
					)
					(number "2"
						(effects
							(font
								(size 1.27 1.27)
							)
						)
					)
				)
			)
		)
	(symbol "antmicroResistors0402:R_2k2_0402"
			(pin_numbers
				(hide yes)
			)
			(pin_names
				(hide yes)
			)
			(exclude_from_sim no)
			(in_bom yes)
			(on_board yes)
			(property "Reference" "R"
				(at 20.32 -5.08 0)
				(effects
					(font
						(size 1.27 1.27)
						(thickness 0.15)
					)
					(justify left bottom)
				)
			)
			(property "Value" "R_2k2_0402"
				(at 20.32 -12.7 0)
				(effects
					(font
						(size 1.27 1.27)
						(thickness 0.15)
					)
					(justify left bottom)
					(hide yes)
				)
			)
			(property "Footprint" "antmicro-footprints:R_0402_1005Metric"
				(at 20.32 -15.24 0)
				(effects
					(font
						(size 1.27 1.27)
						(thickness 0.15)
					)
					(justify left bottom)
					(hide yes)
				)
			)
			(property "Datasheet" "https://www.bourns.com/docs/product-datasheets/cr.pdf"
				(at 20.32 -17.78 0)
				(effects
					(font
						(size 1.27 1.27)
						(thickness 0.15)
					)
					(justify left bottom)
					(hide yes)
				)
			)
			(property "Description" "SMD Chip Resistor, 2.2 kohm, ± 1%, 62.5 mW, 0402 [1005 Metric], Thick Film, General Purpose"
				(at 20.32 -30.48 0)
				(effects
					(font
						(size 1.27 1.27)
					)
					(justify left bottom)
					(hide yes)
				)
			)
			(property "MPN" "CR0402-FX-2201GLF"
				(at 20.32 -20.32 0)
				(effects
					(font
						(size 1.27 1.27)
						(thickness 0.15)
					)
					(justify left bottom)
					(hide yes)
				)
			)
			(property "Manufacturer" "Bourns"
				(at 20.32 -22.86 0)
				(effects
					(font
						(size 1.27 1.27)
						(thickness 0.15)
					)
					(justify left bottom)
					(hide yes)
				)
			)
			(property "License" "Apache-2.0"
				(at 20.32 -25.4 0)
				(effects
					(font
						(size 1.27 1.27)
						(thickness 0.15)
					)
					(justify left bottom)
					(hide yes)
				)
			)
			(property "Author" "Antmicro"
				(at 20.32 -27.94 0)
				(effects
					(font
						(size 1.27 1.27)
						(thickness 0.15)
					)
					(justify left bottom)
					(hide yes)
				)
			)
			(property "Val" "2k2"
				(at 20.32 -7.62 0)
				(effects
					(font
						(size 1.27 1.27)
						(thickness 0.15)
					)
					(justify left bottom)
				)
			)
			(property "Tolerance" "1%"
				(at 20.32 -10.16 0)
				(effects
					(font
						(size 1.27 1.27)
					)
					(justify left bottom)
					(hide yes)
				)
			)
			(property "ki_keywords" "0402, SMT, RESISTOR, PASSIVE"
				(at 0 0 0)
				(effects
					(font
						(size 1.27 1.27)
					)
					(hide yes)
				)
			)
			(symbol "R_2k2_0402_0_1"
				(rectangle
					(start 0.635 0.889)
					(end 4.445 -0.889)
					(stroke
						(width 0.254)
						(type default)
					)
					(fill
						(type none)
					)
				)
			)
			(symbol "R_2k2_0402_1_1"
				(pin passive line
					(at 0 0 0)
					(length 0.635)
					(name "~"
						(effects
							(font
								(size 1.27 1.27)
							)
						)
					)
					(number "1"
						(effects
							(font
								(size 1.27 1.27)
							)
						)
					)
				)
				(pin passive line
					(at 5.08 0 180)
					(length 0.635)
					(name "~"
						(effects
							(font
								(size 1.27 1.27)
							)
						)
					)
					(number "2"
						(effects
							(font
								(size 1.27 1.27)
							)
						)
					)
				)
			)
		)
	(symbol "antmicroResistors0402:R_33k_0402"
			(pin_numbers
				(hide yes)
			)
			(pin_names
				(hide yes)
			)
			(exclude_from_sim no)
			(in_bom yes)
			(on_board yes)
			(property "Reference" "R"
				(at 20.32 -5.08 0)
				(effects
					(font
						(size 1.27 1.27)
						(thickness 0.15)
					)
					(justify left bottom)
				)
			)
			(property "Value" "R_33k_0402"
				(at 20.32 -12.7 0)
				(effects
					(font
						(size 1.27 1.27)
						(thickness 0.15)
					)
					(justify left bottom)
					(hide yes)
				)
			)
			(property "Footprint" "antmicro-footprints:R_0402_1005Metric"
				(at 20.32 -15.24 0)
				(effects
					(font
						(size 1.27 1.27)
						(thickness 0.15)
					)
					(justify left bottom)
					(hide yes)
				)
			)
			(property "Datasheet" "https://www.bourns.com/docs/product-datasheets/cr.pdf"
				(at 20.32 -17.78 0)
				(effects
					(font
						(size 1.27 1.27)
						(thickness 0.15)
					)
					(justify left bottom)
					(hide yes)
				)
			)
			(property "Description" "SMD Chip Resistor, 33 kohm, ± 1%, 62.5 mW, 0402 [1005 Metric], Thick Film, General Purpose"
				(at 20.32 -30.48 0)
				(effects
					(font
						(size 1.27 1.27)
					)
					(justify left bottom)
					(hide yes)
				)
			)
			(property "MPN" "CR0402-FX-3302GLF"
				(at 20.32 -20.32 0)
				(effects
					(font
						(size 1.27 1.27)
						(thickness 0.15)
					)
					(justify left bottom)
					(hide yes)
				)
			)
			(property "Manufacturer" "Bourns"
				(at 20.32 -22.86 0)
				(effects
					(font
						(size 1.27 1.27)
						(thickness 0.15)
					)
					(justify left bottom)
					(hide yes)
				)
			)
			(property "License" "Apache-2.0"
				(at 20.32 -25.4 0)
				(effects
					(font
						(size 1.27 1.27)
						(thickness 0.15)
					)
					(justify left bottom)
					(hide yes)
				)
			)
			(property "Author" "Antmicro"
				(at 20.32 -27.94 0)
				(effects
					(font
						(size 1.27 1.27)
						(thickness 0.15)
					)
					(justify left bottom)
					(hide yes)
				)
			)
			(property "Val" "33k"
				(at 20.32 -7.62 0)
				(effects
					(font
						(size 1.27 1.27)
						(thickness 0.15)
					)
					(justify left bottom)
				)
			)
			(property "Tolerance" "1%"
				(at 20.32 -10.16 0)
				(effects
					(font
						(size 1.27 1.27)
					)
					(justify left bottom)
					(hide yes)
				)
			)
			(property "ki_keywords" "0402, SMT, RESISTOR, PASSIVE"
				(at 0 0 0)
				(effects
					(font
						(size 1.27 1.27)
					)
					(hide yes)
				)
			)
			(symbol "R_33k_0402_0_1"
				(rectangle
					(start 0.635 0.889)
					(end 4.445 -0.889)
					(stroke
						(width 0.254)
						(type default)
					)
					(fill
						(type none)
					)
				)
			)
			(symbol "R_33k_0402_1_1"
				(pin passive line
					(at 0 0 0)
					(length 0.635)
					(name "~"
						(effects
							(font
								(size 1.27 1.27)
							)
						)
					)
					(number "1"
						(effects
							(font
								(size 1.27 1.27)
							)
						)
					)
				)
				(pin passive line
					(at 5.08 0 180)
					(length 0.635)
					(name "~"
						(effects
							(font
								(size 1.27 1.27)
							)
						)
					)
					(number "2"
						(effects
							(font
								(size 1.27 1.27)
							)
						)
					)
				)
			)
		)
	(symbol "antmicroResistors0402:R_37R4_0402"
			(pin_numbers
				(hide yes)
			)
			(pin_names
				(hide yes)
			)
			(exclude_from_sim no)
			(in_bom yes)
			(on_board yes)
			(property "Reference" "R"
				(at 20.32 -5.08 0)
				(effects
					(font
						(size 1.27 1.27)
						(thickness 0.15)
					)
					(justify left bottom)
				)
			)
			(property "Value" "R_37R4_0402"
				(at 20.32 -12.7 0)
				(effects
					(font
						(size 1.27 1.27)
						(thickness 0.15)
					)
					(justify left bottom)
					(hide yes)
				)
			)
			(property "Footprint" "antmicro-footprints:R_0402_1005Metric"
				(at 20.32 -15.24 0)
				(effects
					(font
						(size 1.27 1.27)
						(thickness 0.15)
					)
					(justify left bottom)
					(hide yes)
				)
			)
			(property "Datasheet" "https://www.bourns.com/docs/product-datasheets/cr.pdf"
				(at 20.32 -17.78 0)
				(effects
					(font
						(size 1.27 1.27)
						(thickness 0.15)
					)
					(justify left bottom)
					(hide yes)
				)
			)
			(property "Description" "SMD Chip Resistor, 37.4 ohm, ± 1%, 100 mW, 0402 [1005 Metric], Thick Film, Precision"
				(at 20.32 -30.48 0)
				(effects
					(font
						(size 1.27 1.27)
					)
					(justify left bottom)
					(hide yes)
				)
			)
			(property "MPN" "CR0402-FX-37R4GLF"
				(at 20.32 -20.32 0)
				(effects
					(font
						(size 1.27 1.27)
						(thickness 0.15)
					)
					(justify left bottom)
					(hide yes)
				)
			)
			(property "Manufacturer" "Bourns"
				(at 20.32 -22.86 0)
				(effects
					(font
						(size 1.27 1.27)
						(thickness 0.15)
					)
					(justify left bottom)
					(hide yes)
				)
			)
			(property "License" "Apache-2.0"
				(at 20.32 -25.4 0)
				(effects
					(font
						(size 1.27 1.27)
						(thickness 0.15)
					)
					(justify left bottom)
					(hide yes)
				)
			)
			(property "Author" "Antmicro"
				(at 20.32 -27.94 0)
				(effects
					(font
						(size 1.27 1.27)
						(thickness 0.15)
					)
					(justify left bottom)
					(hide yes)
				)
			)
			(property "Val" "37R4"
				(at 20.32 -7.62 0)
				(effects
					(font
						(size 1.27 1.27)
						(thickness 0.15)
					)
					(justify left bottom)
				)
			)
			(property "Tolerance" "1%"
				(at 20.32 -10.16 0)
				(effects
					(font
						(size 1.27 1.27)
					)
					(justify left bottom)
					(hide yes)
				)
			)
			(property "ki_keywords" "0402, SMT, RESISTOR, PASSIVE"
				(at 0 0 0)
				(effects
					(font
						(size 1.27 1.27)
					)
					(hide yes)
				)
			)
			(symbol "R_37R4_0402_0_1"
				(rectangle
					(start 0.635 0.889)
					(end 4.445 -0.889)
					(stroke
						(width 0.254)
						(type default)
					)
					(fill
						(type none)
					)
				)
			)
			(symbol "R_37R4_0402_1_1"
				(pin passive line
					(at 0 0 0)
					(length 0.635)
					(name "~"
						(effects
							(font
								(size 1.27 1.27)
							)
						)
					)
					(number "1"
						(effects
							(font
								(size 1.27 1.27)
							)
						)
					)
				)
				(pin passive line
					(at 5.08 0 180)
					(length 0.635)
					(name "~"
						(effects
							(font
								(size 1.27 1.27)
							)
						)
					)
					(number "2"
						(effects
							(font
								(size 1.27 1.27)
							)
						)
					)
				)
			)
		)
	(symbol "antmicroResistors0402:R_3k01_0402"
			(pin_numbers
				(hide yes)
			)
			(pin_names
				(hide yes)
			)
			(exclude_from_sim no)
			(in_bom yes)
			(on_board yes)
			(property "Reference" "R"
				(at 20.32 -5.08 0)
				(effects
					(font
						(size 1.27 1.27)
						(thickness 0.15)
					)
					(justify left bottom)
				)
			)
			(property "Value" "R_3k01_0402"
				(at 20.32 -12.7 0)
				(effects
					(font
						(size 1.27 1.27)
						(thickness 0.15)
					)
					(justify left bottom)
					(hide yes)
				)
			)
			(property "Footprint" "antmicro-footprints:R_0402_1005Metric"
				(at 20.32 -15.24 0)
				(effects
					(font
						(size 1.27 1.27)
						(thickness 0.15)
					)
					(justify left bottom)
					(hide yes)
				)
			)
			(property "Datasheet" "https://www.bourns.com/docs/product-datasheets/cr.pdf"
				(at 20.32 -17.78 0)
				(effects
					(font
						(size 1.27 1.27)
						(thickness 0.15)
					)
					(justify left bottom)
					(hide yes)
				)
			)
			(property "Description" "SMD Chip Resistor, 3.01 kohm, ± 1%, 62.5 mW, 0402 [1005 Metric], Thick Film, General Purpose"
				(at 20.32 -30.48 0)
				(effects
					(font
						(size 1.27 1.27)
					)
					(justify left bottom)
					(hide yes)
				)
			)
			(property "MPN" "CR0402-FX-3011GLF"
				(at 20.32 -20.32 0)
				(effects
					(font
						(size 1.27 1.27)
						(thickness 0.15)
					)
					(justify left bottom)
					(hide yes)
				)
			)
			(property "Manufacturer" "Bourns"
				(at 20.32 -22.86 0)
				(effects
					(font
						(size 1.27 1.27)
						(thickness 0.15)
					)
					(justify left bottom)
					(hide yes)
				)
			)
			(property "License" "Apache-2.0"
				(at 20.32 -25.4 0)
				(effects
					(font
						(size 1.27 1.27)
						(thickness 0.15)
					)
					(justify left bottom)
					(hide yes)
				)
			)
			(property "Author" "Antmicro"
				(at 20.32 -27.94 0)
				(effects
					(font
						(size 1.27 1.27)
						(thickness 0.15)
					)
					(justify left bottom)
					(hide yes)
				)
			)
			(property "Val" "3k01"
				(at 20.32 -7.62 0)
				(effects
					(font
						(size 1.27 1.27)
						(thickness 0.15)
					)
					(justify left bottom)
				)
			)
			(property "Tolerance" "1%"
				(at 20.32 -10.16 0)
				(effects
					(font
						(size 1.27 1.27)
					)
					(justify left bottom)
					(hide yes)
				)
			)
			(property "ki_keywords" "0402, SMT, RESISTOR, PASSIVE"
				(at 0 0 0)
				(effects
					(font
						(size 1.27 1.27)
					)
					(hide yes)
				)
			)
			(symbol "R_3k01_0402_0_1"
				(rectangle
					(start 0.635 0.889)
					(end 4.445 -0.889)
					(stroke
						(width 0.254)
						(type default)
					)
					(fill
						(type none)
					)
				)
			)
			(symbol "R_3k01_0402_1_1"
				(pin passive line
					(at 0 0 0)
					(length 0.635)
					(name "~"
						(effects
							(font
								(size 1.27 1.27)
							)
						)
					)
					(number "1"
						(effects
							(font
								(size 1.27 1.27)
							)
						)
					)
				)
				(pin passive line
					(at 5.08 0 180)
					(length 0.635)
					(name "~"
						(effects
							(font
								(size 1.27 1.27)
							)
						)
					)
					(number "2"
						(effects
							(font
								(size 1.27 1.27)
							)
						)
					)
				)
			)
		)
	(symbol "antmicroResistors0402:R_470R_0402"
			(pin_numbers
				(hide yes)
			)
			(pin_names
				(hide yes)
			)
			(exclude_from_sim no)
			(in_bom yes)
			(on_board yes)
			(property "Reference" "R"
				(at 20.32 -5.08 0)
				(effects
					(font
						(size 1.27 1.27)
						(thickness 0.15)
					)
					(justify left bottom)
				)
			)
			(property "Value" "R_470R_0402"
				(at 20.32 -12.7 0)
				(effects
					(font
						(size 1.27 1.27)
						(thickness 0.15)
					)
					(justify left bottom)
					(hide yes)
				)
			)
			(property "Footprint" "antmicro-footprints:R_0402_1005Metric"
				(at 20.32 -15.24 0)
				(effects
					(font
						(size 1.27 1.27)
						(thickness 0.15)
					)
					(justify left bottom)
					(hide yes)
				)
			)
			(property "Datasheet" "https://www.bourns.com/docs/product-datasheets/cr.pdf"
				(at 20.32 -17.78 0)
				(effects
					(font
						(size 1.27 1.27)
						(thickness 0.15)
					)
					(justify left bottom)
					(hide yes)
				)
			)
			(property "Description" "SMD Chip Resistor, 470 ohm, ± 1%, 62.5 mW, 0402 [1005 Metric], Thick Film, General Purpose"
				(at 20.32 -30.48 0)
				(effects
					(font
						(size 1.27 1.27)
					)
					(justify left bottom)
					(hide yes)
				)
			)
			(property "MPN" "CR0402-FX-4700GLF"
				(at 20.32 -20.32 0)
				(effects
					(font
						(size 1.27 1.27)
						(thickness 0.15)
					)
					(justify left bottom)
					(hide yes)
				)
			)
			(property "Manufacturer" "Bourns"
				(at 20.32 -22.86 0)
				(effects
					(font
						(size 1.27 1.27)
						(thickness 0.15)
					)
					(justify left bottom)
					(hide yes)
				)
			)
			(property "License" "Apache-2.0"
				(at 20.32 -25.4 0)
				(effects
					(font
						(size 1.27 1.27)
						(thickness 0.15)
					)
					(justify left bottom)
					(hide yes)
				)
			)
			(property "Author" "Antmicro"
				(at 20.32 -27.94 0)
				(effects
					(font
						(size 1.27 1.27)
						(thickness 0.15)
					)
					(justify left bottom)
					(hide yes)
				)
			)
			(property "Val" "470R"
				(at 20.32 -7.62 0)
				(effects
					(font
						(size 1.27 1.27)
						(thickness 0.15)
					)
					(justify left bottom)
				)
			)
			(property "Tolerance" "1%"
				(at 20.32 -10.16 0)
				(effects
					(font
						(size 1.27 1.27)
					)
					(justify left bottom)
					(hide yes)
				)
			)
			(property "ki_keywords" "0402, SMT, RESISTOR, PASSIVE"
				(at 0 0 0)
				(effects
					(font
						(size 1.27 1.27)
					)
					(hide yes)
				)
			)
			(symbol "R_470R_0402_0_1"
				(rectangle
					(start 0.635 0.889)
					(end 4.445 -0.889)
					(stroke
						(width 0.254)
						(type default)
					)
					(fill
						(type none)
					)
				)
			)
			(symbol "R_470R_0402_1_1"
				(pin passive line
					(at 0 0 0)
					(length 0.635)
					(name "~"
						(effects
							(font
								(size 1.27 1.27)
							)
						)
					)
					(number "1"
						(effects
							(font
								(size 1.27 1.27)
							)
						)
					)
				)
				(pin passive line
					(at 5.08 0 180)
					(length 0.635)
					(name "~"
						(effects
							(font
								(size 1.27 1.27)
							)
						)
					)
					(number "2"
						(effects
							(font
								(size 1.27 1.27)
							)
						)
					)
				)
			)
		)
	(symbol "antmicroResistors0402:R_4k7_0402"
			(pin_numbers
				(hide yes)
			)
			(pin_names
				(hide yes)
			)
			(exclude_from_sim no)
			(in_bom yes)
			(on_board yes)
			(property "Reference" "R"
				(at 20.32 -5.08 0)
				(effects
					(font
						(size 1.27 1.27)
						(thickness 0.15)
					)
					(justify left bottom)
				)
			)
			(property "Value" "R_4k7_0402"
				(at 20.32 -12.7 0)
				(effects
					(font
						(size 1.27 1.27)
						(thickness 0.15)
					)
					(justify left bottom)
					(hide yes)
				)
			)
			(property "Footprint" "antmicro-footprints:R_0402_1005Metric"
				(at 20.32 -15.24 0)
				(effects
					(font
						(size 1.27 1.27)
						(thickness 0.15)
					)
					(justify left bottom)
					(hide yes)
				)
			)
			(property "Datasheet" "https://www.bourns.com/docs/product-datasheets/cr.pdf"
				(at 20.32 -17.78 0)
				(effects
					(font
						(size 1.27 1.27)
						(thickness 0.15)
					)
					(justify left bottom)
					(hide yes)
				)
			)
			(property "Description" "SMD Chip Resistor, 4.7 kohm, ± 1%, 62.5 mW, 0402 [1005 Metric], Thick Film, General Purpose"
				(at 20.32 -30.48 0)
				(effects
					(font
						(size 1.27 1.27)
					)
					(justify left bottom)
					(hide yes)
				)
			)
			(property "MPN" "CR0402-FX-4701GLF"
				(at 20.32 -20.32 0)
				(effects
					(font
						(size 1.27 1.27)
						(thickness 0.15)
					)
					(justify left bottom)
					(hide yes)
				)
			)
			(property "Manufacturer" "Bourns"
				(at 20.32 -22.86 0)
				(effects
					(font
						(size 1.27 1.27)
						(thickness 0.15)
					)
					(justify left bottom)
					(hide yes)
				)
			)
			(property "License" "Apache-2.0"
				(at 20.32 -25.4 0)
				(effects
					(font
						(size 1.27 1.27)
						(thickness 0.15)
					)
					(justify left bottom)
					(hide yes)
				)
			)
			(property "Author" "Antmicro"
				(at 20.32 -27.94 0)
				(effects
					(font
						(size 1.27 1.27)
						(thickness 0.15)
					)
					(justify left bottom)
					(hide yes)
				)
			)
			(property "Val" "4k7"
				(at 20.32 -7.62 0)
				(effects
					(font
						(size 1.27 1.27)
						(thickness 0.15)
					)
					(justify left bottom)
				)
			)
			(property "Tolerance" "1%"
				(at 20.32 -10.16 0)
				(effects
					(font
						(size 1.27 1.27)
					)
					(justify left bottom)
					(hide yes)
				)
			)
			(property "ki_keywords" "0402, SMT, RESISTOR, PASSIVE"
				(at 0 0 0)
				(effects
					(font
						(size 1.27 1.27)
					)
					(hide yes)
				)
			)
			(symbol "R_4k7_0402_0_1"
				(rectangle
					(start 0.635 0.889)
					(end 4.445 -0.889)
					(stroke
						(width 0.254)
						(type default)
					)
					(fill
						(type none)
					)
				)
			)
			(symbol "R_4k7_0402_1_1"
				(pin passive line
					(at 0 0 0)
					(length 0.635)
					(name "~"
						(effects
							(font
								(size 1.27 1.27)
							)
						)
					)
					(number "1"
						(effects
							(font
								(size 1.27 1.27)
							)
						)
					)
				)
				(pin passive line
					(at 5.08 0 180)
					(length 0.635)
					(name "~"
						(effects
							(font
								(size 1.27 1.27)
							)
						)
					)
					(number "2"
						(effects
							(font
								(size 1.27 1.27)
							)
						)
					)
				)
			)
		)
	(symbol "antmicroResistors0402:R_5k1_0402"
			(pin_numbers
				(hide yes)
			)
			(pin_names
				(hide yes)
			)
			(exclude_from_sim no)
			(in_bom yes)
			(on_board yes)
			(property "Reference" "R"
				(at 20.32 -5.08 0)
				(effects
					(font
						(size 1.27 1.27)
						(thickness 0.15)
					)
					(justify left bottom)
				)
			)
			(property "Value" "R_5k1_0402"
				(at 20.32 -12.7 0)
				(effects
					(font
						(size 1.27 1.27)
						(thickness 0.15)
					)
					(justify left bottom)
					(hide yes)
				)
			)
			(property "Footprint" "antmicro-footprints:R_0402_1005Metric"
				(at 20.32 -15.24 0)
				(effects
					(font
						(size 1.27 1.27)
						(thickness 0.15)
					)
					(justify left bottom)
					(hide yes)
				)
			)
			(property "Datasheet" "https://www.bourns.com/docs/product-datasheets/cr.pdf"
				(at 20.32 -17.78 0)
				(effects
					(font
						(size 1.27 1.27)
						(thickness 0.15)
					)
					(justify left bottom)
					(hide yes)
				)
			)
			(property "Description" "SMD Chip Resistor, 5.1 kohm, ± 1%, 63 mW, 0402 [1005 Metric], Thick Film, General Purpose"
				(at 20.32 -30.48 0)
				(effects
					(font
						(size 1.27 1.27)
					)
					(justify left bottom)
					(hide yes)
				)
			)
			(property "MPN" "CR0402-FX-5101GLF"
				(at 20.32 -20.32 0)
				(effects
					(font
						(size 1.27 1.27)
						(thickness 0.15)
					)
					(justify left bottom)
					(hide yes)
				)
			)
			(property "Manufacturer" "Bourns"
				(at 20.32 -22.86 0)
				(effects
					(font
						(size 1.27 1.27)
						(thickness 0.15)
					)
					(justify left bottom)
					(hide yes)
				)
			)
			(property "License" "Apache-2.0"
				(at 20.32 -25.4 0)
				(effects
					(font
						(size 1.27 1.27)
						(thickness 0.15)
					)
					(justify left bottom)
					(hide yes)
				)
			)
			(property "Author" "Antmicro"
				(at 20.32 -27.94 0)
				(effects
					(font
						(size 1.27 1.27)
						(thickness 0.15)
					)
					(justify left bottom)
					(hide yes)
				)
			)
			(property "Val" "5k1"
				(at 20.32 -7.62 0)
				(effects
					(font
						(size 1.27 1.27)
						(thickness 0.15)
					)
					(justify left bottom)
				)
			)
			(property "Tolerance" "1%"
				(at 20.32 -10.16 0)
				(effects
					(font
						(size 1.27 1.27)
					)
					(justify left bottom)
					(hide yes)
				)
			)
			(property "ki_keywords" "0402, SMT, RESISTOR, PASSIVE"
				(at 0 0 0)
				(effects
					(font
						(size 1.27 1.27)
					)
					(hide yes)
				)
			)
			(symbol "R_5k1_0402_0_1"
				(rectangle
					(start 0.635 0.889)
					(end 4.445 -0.889)
					(stroke
						(width 0.254)
						(type default)
					)
					(fill
						(type none)
					)
				)
			)
			(symbol "R_5k1_0402_1_1"
				(pin passive line
					(at 0 0 0)
					(length 0.635)
					(name "~"
						(effects
							(font
								(size 1.27 1.27)
							)
						)
					)
					(number "1"
						(effects
							(font
								(size 1.27 1.27)
							)
						)
					)
				)
				(pin passive line
					(at 5.08 0 180)
					(length 0.635)
					(name "~"
						(effects
							(font
								(size 1.27 1.27)
							)
						)
					)
					(number "2"
						(effects
							(font
								(size 1.27 1.27)
							)
						)
					)
				)
			)
		)
	(symbol "antmicroResistors0402:R_750R_0402"
			(pin_numbers
				(hide yes)
			)
			(pin_names
				(hide yes)
			)
			(exclude_from_sim no)
			(in_bom yes)
			(on_board yes)
			(property "Reference" "R"
				(at 20.32 -5.08 0)
				(effects
					(font
						(size 1.27 1.27)
						(thickness 0.15)
					)
					(justify left bottom)
				)
			)
			(property "Value" "R_750R_0402"
				(at 20.32 -12.7 0)
				(effects
					(font
						(size 1.27 1.27)
						(thickness 0.15)
					)
					(justify left bottom)
					(hide yes)
				)
			)
			(property "Footprint" "antmicro-footprints:R_0402_1005Metric"
				(at 20.32 -15.24 0)
				(effects
					(font
						(size 1.27 1.27)
						(thickness 0.15)
					)
					(justify left bottom)
					(hide yes)
				)
			)
			(property "Datasheet" "https://www.bourns.com/docs/product-datasheets/cr.pdf"
				(at 20.32 -17.78 0)
				(effects
					(font
						(size 1.27 1.27)
						(thickness 0.15)
					)
					(justify left bottom)
					(hide yes)
				)
			)
			(property "Description" "SMD Chip Resistor, 750 ohm, ± 1%, 63 mW, 0402 [1005 Metric], Thick Film, General Purpose"
				(at 20.32 -30.48 0)
				(effects
					(font
						(size 1.27 1.27)
					)
					(justify left bottom)
					(hide yes)
				)
			)
			(property "MPN" "CR0402-FX-7500GLF"
				(at 20.32 -20.32 0)
				(effects
					(font
						(size 1.27 1.27)
						(thickness 0.15)
					)
					(justify left bottom)
					(hide yes)
				)
			)
			(property "Manufacturer" "Bourns"
				(at 20.32 -22.86 0)
				(effects
					(font
						(size 1.27 1.27)
						(thickness 0.15)
					)
					(justify left bottom)
					(hide yes)
				)
			)
			(property "License" "Apache-2.0"
				(at 20.32 -25.4 0)
				(effects
					(font
						(size 1.27 1.27)
						(thickness 0.15)
					)
					(justify left bottom)
					(hide yes)
				)
			)
			(property "Author" "Antmicro"
				(at 20.32 -27.94 0)
				(effects
					(font
						(size 1.27 1.27)
						(thickness 0.15)
					)
					(justify left bottom)
					(hide yes)
				)
			)
			(property "Val" "750R"
				(at 20.32 -7.62 0)
				(effects
					(font
						(size 1.27 1.27)
						(thickness 0.15)
					)
					(justify left bottom)
				)
			)
			(property "Tolerance" "1%"
				(at 20.32 -10.16 0)
				(effects
					(font
						(size 1.27 1.27)
					)
					(justify left bottom)
					(hide yes)
				)
			)
			(property "ki_keywords" "0402, SMT, RESISTOR, PASSIVE"
				(at 0 0 0)
				(effects
					(font
						(size 1.27 1.27)
					)
					(hide yes)
				)
			)
			(symbol "R_750R_0402_0_1"
				(rectangle
					(start 0.635 0.889)
					(end 4.445 -0.889)
					(stroke
						(width 0.254)
						(type default)
					)
					(fill
						(type none)
					)
				)
			)
			(symbol "R_750R_0402_1_1"
				(pin passive line
					(at 0 0 0)
					(length 0.635)
					(name "~"
						(effects
							(font
								(size 1.27 1.27)
							)
						)
					)
					(number "1"
						(effects
							(font
								(size 1.27 1.27)
							)
						)
					)
				)
				(pin passive line
					(at 5.08 0 180)
					(length 0.635)
					(name "~"
						(effects
							(font
								(size 1.27 1.27)
							)
						)
					)
					(number "2"
						(effects
							(font
								(size 1.27 1.27)
							)
						)
					)
				)
			)
		)
	(symbol "antmicroResistors0402:R_75R_0402"
			(pin_numbers
				(hide yes)
			)
			(pin_names
				(hide yes)
			)
			(exclude_from_sim no)
			(in_bom yes)
			(on_board yes)
			(property "Reference" "R"
				(at 20.32 -5.08 0)
				(effects
					(font
						(size 1.27 1.27)
						(thickness 0.15)
					)
					(justify left bottom)
				)
			)
			(property "Value" "R_75R_0402"
				(at 20.32 -12.7 0)
				(effects
					(font
						(size 1.27 1.27)
						(thickness 0.15)
					)
					(justify left bottom)
					(hide yes)
				)
			)
			(property "Footprint" "antmicro-footprints:R_0402_1005Metric"
				(at 20.32 -15.24 0)
				(effects
					(font
						(size 1.27 1.27)
						(thickness 0.15)
					)
					(justify left bottom)
					(hide yes)
				)
			)
			(property "Datasheet" "https://www.bourns.com/docs/product-datasheets/cr.pdf"
				(at 20.32 -17.78 0)
				(effects
					(font
						(size 1.27 1.27)
						(thickness 0.15)
					)
					(justify left bottom)
					(hide yes)
				)
			)
			(property "Description" "SMD Chip Resistor, 75 ohm, ± 1%, 62.5 mW, 0402 [1005 Metric], Thick Film, General Purpose"
				(at 20.32 -30.48 0)
				(effects
					(font
						(size 1.27 1.27)
					)
					(justify left bottom)
					(hide yes)
				)
			)
			(property "MPN" "CR0402-FX-75R0GLF"
				(at 20.32 -20.32 0)
				(effects
					(font
						(size 1.27 1.27)
						(thickness 0.15)
					)
					(justify left bottom)
					(hide yes)
				)
			)
			(property "Manufacturer" "Bourns"
				(at 20.32 -22.86 0)
				(effects
					(font
						(size 1.27 1.27)
						(thickness 0.15)
					)
					(justify left bottom)
					(hide yes)
				)
			)
			(property "License" "Apache-2.0"
				(at 20.32 -25.4 0)
				(effects
					(font
						(size 1.27 1.27)
						(thickness 0.15)
					)
					(justify left bottom)
					(hide yes)
				)
			)
			(property "Author" "Antmicro"
				(at 20.32 -27.94 0)
				(effects
					(font
						(size 1.27 1.27)
						(thickness 0.15)
					)
					(justify left bottom)
					(hide yes)
				)
			)
			(property "Val" "75R"
				(at 20.32 -7.62 0)
				(effects
					(font
						(size 1.27 1.27)
						(thickness 0.15)
					)
					(justify left bottom)
				)
			)
			(property "Tolerance" "1%"
				(at 20.32 -10.16 0)
				(effects
					(font
						(size 1.27 1.27)
					)
					(justify left bottom)
					(hide yes)
				)
			)
			(property "ki_keywords" "0402, SMT, RESISTOR, PASSIVE"
				(at 0 0 0)
				(effects
					(font
						(size 1.27 1.27)
					)
					(hide yes)
				)
			)
			(symbol "R_75R_0402_0_1"
				(rectangle
					(start 0.635 0.889)
					(end 4.445 -0.889)
					(stroke
						(width 0.254)
						(type default)
					)
					(fill
						(type none)
					)
				)
			)
			(symbol "R_75R_0402_1_1"
				(pin passive line
					(at 0 0 0)
					(length 0.635)
					(name "~"
						(effects
							(font
								(size 1.27 1.27)
							)
						)
					)
					(number "1"
						(effects
							(font
								(size 1.27 1.27)
							)
						)
					)
				)
				(pin passive line
					(at 5.08 0 180)
					(length 0.635)
					(name "~"
						(effects
							(font
								(size 1.27 1.27)
							)
						)
					)
					(number "2"
						(effects
							(font
								(size 1.27 1.27)
							)
						)
					)
				)
			)
		)
	(symbol "antmicroResistors0603:R_0R_0603"
			(pin_numbers
				(hide yes)
			)
			(pin_names
				(hide yes)
			)
			(exclude_from_sim no)
			(in_bom yes)
			(on_board yes)
			(property "Reference" "R"
				(at 20.32 -5.08 0)
				(effects
					(font
						(size 1.27 1.27)
						(thickness 0.15)
					)
					(justify left bottom)
				)
			)
			(property "Value" "R_0R_0603"
				(at 20.32 -12.7 0)
				(effects
					(font
						(size 1.27 1.27)
						(thickness 0.15)
					)
					(justify left bottom)
					(hide yes)
				)
			)
			(property "Footprint" "antmicro-footprints:R_0603_1608Metric"
				(at 20.32 -15.24 0)
				(effects
					(font
						(size 1.27 1.27)
						(thickness 0.15)
					)
					(justify left bottom)
					(hide yes)
				)
			)
			(property "Datasheet" "https://www.bourns.com/docs/product-datasheets/cr.pdf?sfvrsn=574d41f6_14"
				(at 20.32 -17.78 0)
				(effects
					(font
						(size 1.27 1.27)
						(thickness 0.15)
					)
					(justify left bottom)
					(hide yes)
				)
			)
			(property "Description" "Zero Ohm Resistor, Jumper, 0603 [1608 Metric], Thick Film, 100 mW, 1 A, Surface Mount Device, CR"
				(at 20.32 -33.02 0)
				(effects
					(font
						(size 1.27 1.27)
					)
					(justify left bottom)
					(hide yes)
				)
			)
			(property "MPN" "CR0603-J/-000ELF"
				(at 20.32 -20.32 0)
				(effects
					(font
						(size 1.27 1.27)
						(thickness 0.15)
					)
					(justify left bottom)
					(hide yes)
				)
			)
			(property "Manufacturer" "Bourns"
				(at 20.32 -22.86 0)
				(effects
					(font
						(size 1.27 1.27)
						(thickness 0.15)
					)
					(justify left bottom)
					(hide yes)
				)
			)
			(property "License" "Apache-2.0"
				(at 20.32 -25.4 0)
				(effects
					(font
						(size 1.27 1.27)
						(thickness 0.15)
					)
					(justify left bottom)
					(hide yes)
				)
			)
			(property "Author" "Antmicro"
				(at 20.32 -27.94 0)
				(effects
					(font
						(size 1.27 1.27)
						(thickness 0.15)
					)
					(justify left bottom)
					(hide yes)
				)
			)
			(property "Val" "0R"
				(at 20.32 -7.62 0)
				(effects
					(font
						(size 1.27 1.27)
						(thickness 0.15)
					)
					(justify left bottom)
				)
			)
			(property "Tolerance" "~"
				(at 20.32 -10.16 0)
				(effects
					(font
						(size 1.27 1.27)
					)
					(justify left bottom)
					(hide yes)
				)
			)
			(property "Current" "1A"
				(at 20.32 -30.48 0)
				(effects
					(font
						(size 1.27 1.27)
						(thickness 0.15)
					)
					(justify left bottom)
					(hide yes)
				)
			)
			(property "ki_keywords" "0603, SMT, RESISTOR, PASSIVE"
				(at 0 0 0)
				(effects
					(font
						(size 1.27 1.27)
					)
					(hide yes)
				)
			)
			(symbol "R_0R_0603_0_1"
				(rectangle
					(start 0.635 0.889)
					(end 4.445 -0.889)
					(stroke
						(width 0.254)
						(type default)
					)
					(fill
						(type none)
					)
				)
			)
			(symbol "R_0R_0603_1_1"
				(pin passive line
					(at 0 0 0)
					(length 0.635)
					(name "~"
						(effects
							(font
								(size 1.27 1.27)
							)
						)
					)
					(number "1"
						(effects
							(font
								(size 1.27 1.27)
							)
						)
					)
				)
				(pin passive line
					(at 5.08 0 180)
					(length 0.635)
					(name "~"
						(effects
							(font
								(size 1.27 1.27)
							)
						)
					)
					(number "2"
						(effects
							(font
								(size 1.27 1.27)
							)
						)
					)
				)
			)
		)
	(symbol "antmicroResistors0603:R_10k_0603"
			(pin_numbers
				(hide yes)
			)
			(pin_names
				(hide yes)
			)
			(exclude_from_sim no)
			(in_bom yes)
			(on_board yes)
			(property "Reference" "R"
				(at 20.32 -5.08 0)
				(effects
					(font
						(size 1.27 1.27)
						(thickness 0.15)
					)
					(justify left bottom)
				)
			)
			(property "Value" "R_10k_0603"
				(at 20.32 -12.7 0)
				(effects
					(font
						(size 1.27 1.27)
						(thickness 0.15)
					)
					(justify left bottom)
					(hide yes)
				)
			)
			(property "Footprint" "antmicro-footprints:R_0603_1608Metric"
				(at 20.32 -15.24 0)
				(effects
					(font
						(size 1.27 1.27)
						(thickness 0.15)
					)
					(justify left bottom)
					(hide yes)
				)
			)
			(property "Datasheet" "https://www.bourns.com/docs/product-datasheets/cr.pdf"
				(at 20.32 -17.78 0)
				(effects
					(font
						(size 1.27 1.27)
						(thickness 0.15)
					)
					(justify left bottom)
					(hide yes)
				)
			)
			(property "Description" "SMD Chip Resistor, 10 kohm, ± 1%, 100 mW, 0603 [1608 Metric], Thick Film, General Purpose"
				(at 20.32 -30.48 0)
				(effects
					(font
						(size 1.27 1.27)
					)
					(justify left bottom)
					(hide yes)
				)
			)
			(property "MPN" "CR0603-FX-1002ELF"
				(at 20.32 -20.32 0)
				(effects
					(font
						(size 1.27 1.27)
						(thickness 0.15)
					)
					(justify left bottom)
					(hide yes)
				)
			)
			(property "Manufacturer" "Bourns"
				(at 20.32 -22.86 0)
				(effects
					(font
						(size 1.27 1.27)
						(thickness 0.15)
					)
					(justify left bottom)
					(hide yes)
				)
			)
			(property "License" "Apache-2.0"
				(at 20.32 -25.4 0)
				(effects
					(font
						(size 1.27 1.27)
						(thickness 0.15)
					)
					(justify left bottom)
					(hide yes)
				)
			)
			(property "Author" "Antmicro"
				(at 20.32 -27.94 0)
				(effects
					(font
						(size 1.27 1.27)
						(thickness 0.15)
					)
					(justify left bottom)
					(hide yes)
				)
			)
			(property "Val" "10k"
				(at 20.32 -7.62 0)
				(effects
					(font
						(size 1.27 1.27)
						(thickness 0.15)
					)
					(justify left bottom)
				)
			)
			(property "Tolerance" "1%"
				(at 20.32 -10.16 0)
				(effects
					(font
						(size 1.27 1.27)
					)
					(justify left bottom)
					(hide yes)
				)
			)
			(property "ki_keywords" "0603, SMT, RESISTOR, PASSIVE"
				(at 0 0 0)
				(effects
					(font
						(size 1.27 1.27)
					)
					(hide yes)
				)
			)
			(symbol "R_10k_0603_0_1"
				(rectangle
					(start 0.635 0.889)
					(end 4.445 -0.889)
					(stroke
						(width 0.254)
						(type default)
					)
					(fill
						(type none)
					)
				)
			)
			(symbol "R_10k_0603_1_1"
				(pin passive line
					(at 0 0 0)
					(length 0.635)
					(name "~"
						(effects
							(font
								(size 1.27 1.27)
							)
						)
					)
					(number "1"
						(effects
							(font
								(size 1.27 1.27)
							)
						)
					)
				)
				(pin passive line
					(at 5.08 0 180)
					(length 0.635)
					(name "~"
						(effects
							(font
								(size 1.27 1.27)
							)
						)
					)
					(number "2"
						(effects
							(font
								(size 1.27 1.27)
							)
						)
					)
				)
			)
		)
	(symbol "antmicroResistors0603:R_15k_0603"
			(pin_numbers
				(hide yes)
			)
			(pin_names
				(hide yes)
			)
			(exclude_from_sim no)
			(in_bom yes)
			(on_board yes)
			(property "Reference" "R"
				(at 20.32 -5.08 0)
				(effects
					(font
						(size 1.27 1.27)
						(thickness 0.15)
					)
					(justify left bottom)
				)
			)
			(property "Value" "R_15k_0603"
				(at 20.32 -12.7 0)
				(effects
					(font
						(size 1.27 1.27)
						(thickness 0.15)
					)
					(justify left bottom)
					(hide yes)
				)
			)
			(property "Footprint" "antmicro-footprints:R_0603_1608Metric"
				(at 20.32 -15.24 0)
				(effects
					(font
						(size 1.27 1.27)
						(thickness 0.15)
					)
					(justify left bottom)
					(hide yes)
				)
			)
			(property "Datasheet" "https://www.bourns.com/docs/product-datasheets/cr.pdf"
				(at 20.32 -17.78 0)
				(effects
					(font
						(size 1.27 1.27)
						(thickness 0.15)
					)
					(justify left bottom)
					(hide yes)
				)
			)
			(property "Description" "SMD Chip Resistor, 15 kohm, ± 1%, 100 mW, 0603 [1608 Metric], Thick Film, General Purpose"
				(at 20.32 -30.48 0)
				(effects
					(font
						(size 1.27 1.27)
					)
					(justify left bottom)
					(hide yes)
				)
			)
			(property "MPN" "CR0603-FX-1502ELF"
				(at 20.32 -20.32 0)
				(effects
					(font
						(size 1.27 1.27)
						(thickness 0.15)
					)
					(justify left bottom)
					(hide yes)
				)
			)
			(property "Manufacturer" "Bourns"
				(at 20.32 -22.86 0)
				(effects
					(font
						(size 1.27 1.27)
						(thickness 0.15)
					)
					(justify left bottom)
					(hide yes)
				)
			)
			(property "License" "Apache-2.0"
				(at 20.32 -25.4 0)
				(effects
					(font
						(size 1.27 1.27)
						(thickness 0.15)
					)
					(justify left bottom)
					(hide yes)
				)
			)
			(property "Author" "Antmicro"
				(at 20.32 -27.94 0)
				(effects
					(font
						(size 1.27 1.27)
						(thickness 0.15)
					)
					(justify left bottom)
					(hide yes)
				)
			)
			(property "Val" "15k"
				(at 20.32 -7.62 0)
				(effects
					(font
						(size 1.27 1.27)
						(thickness 0.15)
					)
					(justify left bottom)
				)
			)
			(property "Tolerance" "1%"
				(at 20.32 -10.16 0)
				(effects
					(font
						(size 1.27 1.27)
					)
					(justify left bottom)
					(hide yes)
				)
			)
			(property "ki_keywords" "0603, SMT, RESISTOR, PASSIVE"
				(at 0 0 0)
				(effects
					(font
						(size 1.27 1.27)
					)
					(hide yes)
				)
			)
			(symbol "R_15k_0603_0_1"
				(rectangle
					(start 0.635 0.889)
					(end 4.445 -0.889)
					(stroke
						(width 0.254)
						(type default)
					)
					(fill
						(type none)
					)
				)
			)
			(symbol "R_15k_0603_1_1"
				(pin passive line
					(at 0 0 0)
					(length 0.635)
					(name "~"
						(effects
							(font
								(size 1.27 1.27)
							)
						)
					)
					(number "1"
						(effects
							(font
								(size 1.27 1.27)
							)
						)
					)
				)
				(pin passive line
					(at 5.08 0 180)
					(length 0.635)
					(name "~"
						(effects
							(font
								(size 1.27 1.27)
							)
						)
					)
					(number "2"
						(effects
							(font
								(size 1.27 1.27)
							)
						)
					)
				)
			)
		)
	(symbol "antmicroResistors0603:R_200R_0603"
			(pin_numbers
				(hide yes)
			)
			(pin_names
				(hide yes)
			)
			(exclude_from_sim no)
			(in_bom yes)
			(on_board yes)
			(property "Reference" "R"
				(at 20.32 -5.08 0)
				(effects
					(font
						(size 1.27 1.27)
						(thickness 0.15)
					)
					(justify left bottom)
				)
			)
			(property "Value" "R_200R_0603"
				(at 20.32 -12.7 0)
				(effects
					(font
						(size 1.27 1.27)
						(thickness 0.15)
					)
					(justify left bottom)
					(hide yes)
				)
			)
			(property "Footprint" "antmicro-footprints:R_0603_1608Metric"
				(at 20.32 -15.24 0)
				(effects
					(font
						(size 1.27 1.27)
						(thickness 0.15)
					)
					(justify left bottom)
					(hide yes)
				)
			)
			(property "Datasheet" "https://www.bourns.com/docs/product-datasheets/cr.pdf"
				(at 20.32 -17.78 0)
				(effects
					(font
						(size 1.27 1.27)
						(thickness 0.15)
					)
					(justify left bottom)
					(hide yes)
				)
			)
			(property "Description" "SMD Chip Resistor, 200 ohm, ± 1%, 100 mW, 0603 [1608 Metric], Thick Film, General Purpose"
				(at 20.32 -30.48 0)
				(effects
					(font
						(size 1.27 1.27)
					)
					(justify left bottom)
					(hide yes)
				)
			)
			(property "MPN" "CR0603-FX-2000ELF"
				(at 20.32 -20.32 0)
				(effects
					(font
						(size 1.27 1.27)
						(thickness 0.15)
					)
					(justify left bottom)
					(hide yes)
				)
			)
			(property "Manufacturer" "Bourns"
				(at 20.32 -22.86 0)
				(effects
					(font
						(size 1.27 1.27)
						(thickness 0.15)
					)
					(justify left bottom)
					(hide yes)
				)
			)
			(property "License" "Apache-2.0"
				(at 20.32 -25.4 0)
				(effects
					(font
						(size 1.27 1.27)
						(thickness 0.15)
					)
					(justify left bottom)
					(hide yes)
				)
			)
			(property "Author" "Antmicro"
				(at 20.32 -27.94 0)
				(effects
					(font
						(size 1.27 1.27)
						(thickness 0.15)
					)
					(justify left bottom)
					(hide yes)
				)
			)
			(property "Val" "200R"
				(at 20.32 -7.62 0)
				(effects
					(font
						(size 1.27 1.27)
						(thickness 0.15)
					)
					(justify left bottom)
				)
			)
			(property "Tolerance" "1%"
				(at 20.32 -10.16 0)
				(effects
					(font
						(size 1.27 1.27)
					)
					(justify left bottom)
					(hide yes)
				)
			)
			(property "ki_keywords" "0603, SMT, RESISTOR, PASSIVE"
				(at 0 0 0)
				(effects
					(font
						(size 1.27 1.27)
					)
					(hide yes)
				)
			)
			(symbol "R_200R_0603_0_1"
				(rectangle
					(start 0.635 0.889)
					(end 4.445 -0.889)
					(stroke
						(width 0.254)
						(type default)
					)
					(fill
						(type none)
					)
				)
			)
			(symbol "R_200R_0603_1_1"
				(pin passive line
					(at 0 0 0)
					(length 0.635)
					(name "~"
						(effects
							(font
								(size 1.27 1.27)
							)
						)
					)
					(number "1"
						(effects
							(font
								(size 1.27 1.27)
							)
						)
					)
				)
				(pin passive line
					(at 5.08 0 180)
					(length 0.635)
					(name "~"
						(effects
							(font
								(size 1.27 1.27)
							)
						)
					)
					(number "2"
						(effects
							(font
								(size 1.27 1.27)
							)
						)
					)
				)
			)
		)
	(symbol "antmicroResistors0603:R_470R_0603"
			(pin_numbers
				(hide yes)
			)
			(pin_names
				(hide yes)
			)
			(exclude_from_sim no)
			(in_bom yes)
			(on_board yes)
			(property "Reference" "R"
				(at 20.32 -5.08 0)
				(effects
					(font
						(size 1.27 1.27)
						(thickness 0.15)
					)
					(justify left bottom)
				)
			)
			(property "Value" "R_470R_0603"
				(at 20.32 -12.7 0)
				(effects
					(font
						(size 1.27 1.27)
						(thickness 0.15)
					)
					(justify left bottom)
					(hide yes)
				)
			)
			(property "Footprint" "antmicro-footprints:R_0603_1608Metric"
				(at 20.32 -15.24 0)
				(effects
					(font
						(size 1.27 1.27)
						(thickness 0.15)
					)
					(justify left bottom)
					(hide yes)
				)
			)
			(property "Datasheet" "https://www.bourns.com/docs/product-datasheets/cr.pdf"
				(at 20.32 -17.78 0)
				(effects
					(font
						(size 1.27 1.27)
						(thickness 0.15)
					)
					(justify left bottom)
					(hide yes)
				)
			)
			(property "Description" "SMD Chip Resistor, 470 ohm, ± 1%, 100 mW, 0603 [1608 Metric], Thick Film, General Purpose"
				(at 20.32 -30.48 0)
				(effects
					(font
						(size 1.27 1.27)
					)
					(justify left bottom)
					(hide yes)
				)
			)
			(property "MPN" "CR0603-FX-4700ELF"
				(at 20.32 -20.32 0)
				(effects
					(font
						(size 1.27 1.27)
						(thickness 0.15)
					)
					(justify left bottom)
					(hide yes)
				)
			)
			(property "Manufacturer" "Bourns"
				(at 20.32 -22.86 0)
				(effects
					(font
						(size 1.27 1.27)
						(thickness 0.15)
					)
					(justify left bottom)
					(hide yes)
				)
			)
			(property "License" "Apache-2.0"
				(at 20.32 -25.4 0)
				(effects
					(font
						(size 1.27 1.27)
						(thickness 0.15)
					)
					(justify left bottom)
					(hide yes)
				)
			)
			(property "Author" "Antmicro"
				(at 20.32 -27.94 0)
				(effects
					(font
						(size 1.27 1.27)
						(thickness 0.15)
					)
					(justify left bottom)
					(hide yes)
				)
			)
			(property "Val" "470R"
				(at 20.32 -7.62 0)
				(effects
					(font
						(size 1.27 1.27)
						(thickness 0.15)
					)
					(justify left bottom)
				)
			)
			(property "Tolerance" "1%"
				(at 20.32 -10.16 0)
				(effects
					(font
						(size 1.27 1.27)
					)
					(justify left bottom)
					(hide yes)
				)
			)
			(property "ki_keywords" "0603, SMT, RESISTOR, PASSIVE"
				(at 0 0 0)
				(effects
					(font
						(size 1.27 1.27)
					)
					(hide yes)
				)
			)
			(symbol "R_470R_0603_0_1"
				(rectangle
					(start 0.635 0.889)
					(end 4.445 -0.889)
					(stroke
						(width 0.254)
						(type default)
					)
					(fill
						(type none)
					)
				)
			)
			(symbol "R_470R_0603_1_1"
				(pin passive line
					(at 0 0 0)
					(length 0.635)
					(name "~"
						(effects
							(font
								(size 1.27 1.27)
							)
						)
					)
					(number "1"
						(effects
							(font
								(size 1.27 1.27)
							)
						)
					)
				)
				(pin passive line
					(at 5.08 0 180)
					(length 0.635)
					(name "~"
						(effects
							(font
								(size 1.27 1.27)
							)
						)
					)
					(number "2"
						(effects
							(font
								(size 1.27 1.27)
							)
						)
					)
				)
			)
		)
	(symbol "antmicroResistorsmisc:R_0R_0805"
			(pin_numbers
				(hide yes)
			)
			(pin_names
				(hide yes)
			)
			(exclude_from_sim no)
			(in_bom yes)
			(on_board yes)
			(property "Reference" "R"
				(at 20.32 -5.08 0)
				(effects
					(font
						(size 1.27 1.27)
						(thickness 0.15)
					)
					(justify left bottom)
				)
			)
			(property "Value" "R_0R_0805"
				(at 20.32 -12.7 0)
				(effects
					(font
						(size 1.27 1.27)
						(thickness 0.15)
					)
					(justify left bottom)
					(hide yes)
				)
			)
			(property "Footprint" "antmicro-footprints:R_0805_2012Metric"
				(at 20.32 -15.24 0)
				(effects
					(font
						(size 1.27 1.27)
						(thickness 0.15)
					)
					(justify left bottom)
					(hide yes)
				)
			)
			(property "Datasheet" "https://www.vishay.com/docs/20035/dcrcwe3.pdf"
				(at 20.32 -17.78 0)
				(effects
					(font
						(size 1.27 1.27)
						(thickness 0.15)
					)
					(justify left bottom)
					(hide yes)
				)
			)
			(property "Description" "Zero Ohm Resistor, Jumper, 0805 [2012 Metric], Thick Film, 125 mW, 2.5 A, Surface Mount Device"
				(at 20.32 -33.02 0)
				(effects
					(font
						(size 1.27 1.27)
					)
					(justify left bottom)
					(hide yes)
				)
			)
			(property "MPN" "CRCW08050000Z0EA"
				(at 20.32 -20.32 0)
				(effects
					(font
						(size 1.27 1.27)
						(thickness 0.15)
					)
					(justify left bottom)
					(hide yes)
				)
			)
			(property "Manufacturer" "Vishay"
				(at 20.32 -22.86 0)
				(effects
					(font
						(size 1.27 1.27)
						(thickness 0.15)
					)
					(justify left bottom)
					(hide yes)
				)
			)
			(property "License" "Apache-2.0"
				(at 20.32 -25.4 0)
				(effects
					(font
						(size 1.27 1.27)
						(thickness 0.15)
					)
					(justify left bottom)
					(hide yes)
				)
			)
			(property "Author" "Antmicro"
				(at 20.32 -27.94 0)
				(effects
					(font
						(size 1.27 1.27)
						(thickness 0.15)
					)
					(justify left bottom)
					(hide yes)
				)
			)
			(property "Val" "0R"
				(at 20.32 -7.62 0)
				(effects
					(font
						(size 1.27 1.27)
						(thickness 0.15)
					)
					(justify left bottom)
				)
			)
			(property "Tolerance" "~"
				(at 20.32 -10.16 0)
				(effects
					(font
						(size 1.27 1.27)
					)
					(justify left bottom)
					(hide yes)
				)
			)
			(property "Current" "2.5A"
				(at 20.32 -30.48 0)
				(effects
					(font
						(size 1.27 1.27)
						(thickness 0.15)
					)
					(justify left bottom)
					(hide yes)
				)
			)
			(property "ki_keywords" "0805, SMT, RESISTOR, PASSIVE"
				(at 0 0 0)
				(effects
					(font
						(size 1.27 1.27)
					)
					(hide yes)
				)
			)
			(symbol "R_0R_0805_0_1"
				(rectangle
					(start 0.635 0.889)
					(end 4.445 -0.889)
					(stroke
						(width 0.254)
						(type default)
					)
					(fill
						(type none)
					)
				)
			)
			(symbol "R_0R_0805_1_1"
				(pin passive line
					(at 0 0 0)
					(length 0.635)
					(name "~"
						(effects
							(font
								(size 1.27 1.27)
							)
						)
					)
					(number "1"
						(effects
							(font
								(size 1.27 1.27)
							)
						)
					)
				)
				(pin passive line
					(at 5.08 0 180)
					(length 0.635)
					(name "~"
						(effects
							(font
								(size 1.27 1.27)
							)
						)
					)
					(number "2"
						(effects
							(font
								(size 1.27 1.27)
							)
						)
					)
				)
			)
		)
	(symbol "antmicroResistorsmisc:R_0R_1206"
			(pin_numbers
				(hide yes)
			)
			(pin_names
				(hide yes)
			)
			(exclude_from_sim no)
			(in_bom yes)
			(on_board yes)
			(property "Reference" "R"
				(at 20.32 -5.08 0)
				(effects
					(font
						(size 1.27 1.27)
						(thickness 0.15)
					)
					(justify left bottom)
				)
			)
			(property "Value" "R_0R_1206"
				(at 20.32 -12.7 0)
				(effects
					(font
						(size 1.27 1.27)
						(thickness 0.15)
					)
					(justify left bottom)
					(hide yes)
				)
			)
			(property "Footprint" "antmicro-footprints:R_1206_3216Metric"
				(at 20.32 -15.24 0)
				(effects
					(font
						(size 1.27 1.27)
						(thickness 0.15)
					)
					(justify left bottom)
					(hide yes)
				)
			)
			(property "Datasheet" "https://www.farnell.com/datasheets/2860635.pdf"
				(at 20.32 -17.78 0)
				(effects
					(font
						(size 1.27 1.27)
						(thickness 0.15)
					)
					(justify left bottom)
					(hide yes)
				)
			)
			(property "Description" "Zero Ohm Resistor, Jumper, 1206 [3216 Metric], Thick Film, 250 mW, 2 A, Surface Mount Device"
				(at 20.32 -33.02 0)
				(effects
					(font
						(size 1.27 1.27)
					)
					(justify left bottom)
					(hide yes)
				)
			)
			(property "MPN" "MCMR12X000_PTL"
				(at 20.32 -20.32 0)
				(effects
					(font
						(size 1.27 1.27)
						(thickness 0.15)
					)
					(justify left bottom)
					(hide yes)
				)
			)
			(property "Manufacturer" "Multicomp Pro"
				(at 20.32 -22.86 0)
				(effects
					(font
						(size 1.27 1.27)
						(thickness 0.15)
					)
					(justify left bottom)
					(hide yes)
				)
			)
			(property "License" "Apache-2.0"
				(at 20.32 -25.4 0)
				(effects
					(font
						(size 1.27 1.27)
						(thickness 0.15)
					)
					(justify left bottom)
					(hide yes)
				)
			)
			(property "Author" "Antmicro"
				(at 20.32 -27.94 0)
				(effects
					(font
						(size 1.27 1.27)
						(thickness 0.15)
					)
					(justify left bottom)
					(hide yes)
				)
			)
			(property "Val" "0R"
				(at 20.32 -7.62 0)
				(effects
					(font
						(size 1.27 1.27)
						(thickness 0.15)
					)
					(justify left bottom)
				)
			)
			(property "Tolerance" "~"
				(at 20.32 -10.16 0)
				(effects
					(font
						(size 1.27 1.27)
					)
					(justify left bottom)
					(hide yes)
				)
			)
			(property "Current" "2A"
				(at 20.32 -30.48 0)
				(effects
					(font
						(size 1.27 1.27)
						(thickness 0.15)
					)
					(justify left bottom)
					(hide yes)
				)
			)
			(property "ki_keywords" "1206, SMT, RESISTOR, PASSIVE"
				(at 0 0 0)
				(effects
					(font
						(size 1.27 1.27)
					)
					(hide yes)
				)
			)
			(symbol "R_0R_1206_0_1"
				(rectangle
					(start 0.635 0.889)
					(end 4.445 -0.889)
					(stroke
						(width 0.254)
						(type default)
					)
					(fill
						(type none)
					)
				)
			)
			(symbol "R_0R_1206_1_1"
				(pin passive line
					(at 0 0 0)
					(length 0.635)
					(name "~"
						(effects
							(font
								(size 1.27 1.27)
							)
						)
					)
					(number "1"
						(effects
							(font
								(size 1.27 1.27)
							)
						)
					)
				)
				(pin passive line
					(at 5.08 0 180)
					(length 0.635)
					(name "~"
						(effects
							(font
								(size 1.27 1.27)
							)
						)
					)
					(number "2"
						(effects
							(font
								(size 1.27 1.27)
							)
						)
					)
				)
			)
		)
	(symbol "antmicroResistorsmisc:R_100R_0201"
			(pin_numbers
				(hide yes)
			)
			(pin_names
				(hide yes)
			)
			(exclude_from_sim no)
			(in_bom yes)
			(on_board yes)
			(property "Reference" "R"
				(at 20.32 -5.08 0)
				(effects
					(font
						(size 1.27 1.27)
						(thickness 0.15)
					)
					(justify left bottom)
				)
			)
			(property "Value" "R_100R_0201"
				(at 20.32 -12.7 0)
				(effects
					(font
						(size 1.27 1.27)
						(thickness 0.15)
					)
					(justify left bottom)
					(hide yes)
				)
			)
			(property "Footprint" "antmicro-footprints:R_0201"
				(at 20.32 -15.24 0)
				(effects
					(font
						(size 1.27 1.27)
						(thickness 0.15)
					)
					(justify left bottom)
					(hide yes)
				)
			)
			(property "Datasheet" "https://www.bourns.com/docs/product-datasheets/cr-a-as.pdf"
				(at 20.32 -17.78 0)
				(effects
					(font
						(size 1.27 1.27)
						(thickness 0.15)
					)
					(justify left bottom)
					(hide yes)
				)
			)
			(property "Description" "SMD Chip Resistor, 100 ohm, ± 1%, 50 mW, 0201 [0603 Metric], Thick Film, Sulfur Resistant"
				(at 20.32 -30.48 0)
				(effects
					(font
						(size 1.27 1.27)
					)
					(justify left bottom)
					(hide yes)
				)
			)
			(property "MPN" "CR0201AFW-1000GAS"
				(at 20.32 -20.32 0)
				(effects
					(font
						(size 1.27 1.27)
						(thickness 0.15)
					)
					(justify left bottom)
					(hide yes)
				)
			)
			(property "Manufacturer" "Bourns"
				(at 20.32 -22.86 0)
				(effects
					(font
						(size 1.27 1.27)
						(thickness 0.15)
					)
					(justify left bottom)
					(hide yes)
				)
			)
			(property "License" "Apache-2.0"
				(at 20.32 -25.4 0)
				(effects
					(font
						(size 1.27 1.27)
						(thickness 0.15)
					)
					(justify left bottom)
					(hide yes)
				)
			)
			(property "Author" "Antmicro"
				(at 20.32 -27.94 0)
				(effects
					(font
						(size 1.27 1.27)
						(thickness 0.15)
					)
					(justify left bottom)
					(hide yes)
				)
			)
			(property "Val" "100R"
				(at 20.32 -7.62 0)
				(effects
					(font
						(size 1.27 1.27)
						(thickness 0.15)
					)
					(justify left bottom)
				)
			)
			(property "Tolerance" "1%"
				(at 20.32 -10.16 0)
				(effects
					(font
						(size 1.27 1.27)
					)
					(justify left bottom)
					(hide yes)
				)
			)
			(property "ki_keywords" "0201, SMT, RESISTOR, PASSIVE"
				(at 0 0 0)
				(effects
					(font
						(size 1.27 1.27)
					)
					(hide yes)
				)
			)
			(symbol "R_100R_0201_0_1"
				(rectangle
					(start 0.635 0.889)
					(end 4.445 -0.889)
					(stroke
						(width 0.254)
						(type default)
					)
					(fill
						(type none)
					)
				)
			)
			(symbol "R_100R_0201_1_1"
				(pin passive line
					(at 0 0 0)
					(length 0.635)
					(name "~"
						(effects
							(font
								(size 1.27 1.27)
							)
						)
					)
					(number "1"
						(effects
							(font
								(size 1.27 1.27)
							)
						)
					)
				)
				(pin passive line
					(at 5.08 0 180)
					(length 0.635)
					(name "~"
						(effects
							(font
								(size 1.27 1.27)
							)
						)
					)
					(number "2"
						(effects
							(font
								(size 1.27 1.27)
							)
						)
					)
				)
			)
		)
	(symbol "antmicroResonators:Resonator_27MHz_ABM7"
			(pin_names
				(hide yes)
			)
			(exclude_from_sim no)
			(in_bom yes)
			(on_board yes)
			(property "Reference" "Y"
				(at 15.24 -5.08 0)
				(effects
					(font
						(size 1.27 1.27)
						(thickness 0.15)
					)
					(justify left bottom)
				)
			)
			(property "Value" "Resonator_27MHz_ABM7"
				(at 15.24 -12.7 0)
				(effects
					(font
						(size 1.27 1.27)
						(thickness 0.15)
					)
					(justify left bottom)
					(hide yes)
				)
			)
			(property "Footprint" "antmicro-footprints:Resonator_SMD_Abracon_ABM7_6x3.5x1.4mm"
				(at 15.24 -15.24 0)
				(effects
					(font
						(size 1.27 1.27)
						(thickness 0.15)
					)
					(justify left bottom)
					(hide yes)
				)
			)
			(property "Datasheet" "https://abracon.com/Resonators/abm7.pdf"
				(at 15.24 -17.78 0)
				(effects
					(font
						(size 1.27 1.27)
						(thickness 0.15)
					)
					(justify left bottom)
					(hide yes)
				)
			)
			(property "Description" "Crystal, 27 MHz, SMD, 6mm x 3.5mm, 30 ppm, 18 pF, 20 ppm, ABM7"
				(at 15.24 -27.94 0)
				(effects
					(font
						(size 1.27 1.27)
					)
					(justify left bottom)
					(hide yes)
				)
			)
			(property "MPN" "ABM7-27.000MHZ-D2Y-T"
				(at 15.24 -7.62 0)
				(effects
					(font
						(size 1.27 1.27)
						(thickness 0.15)
					)
					(justify left bottom)
				)
			)
			(property "Manufacturer" "Abracon"
				(at 15.24 -20.32 0)
				(effects
					(font
						(size 1.27 1.27)
						(thickness 0.15)
					)
					(justify left bottom)
					(hide yes)
				)
			)
			(property "Author" "Antmicro"
				(at 15.24 -22.86 0)
				(effects
					(font
						(size 1.27 1.27)
						(thickness 0.15)
					)
					(justify left bottom)
					(hide yes)
				)
			)
			(property "License" "Apache-2.0"
				(at 15.24 -25.4 0)
				(effects
					(font
						(size 1.27 1.27)
						(thickness 0.15)
					)
					(justify left bottom)
					(hide yes)
				)
			)
			(property "Val" "27 MHz"
				(at 15.24 -10.16 0)
				(effects
					(font
						(size 1.27 1.27)
						(thickness 0.15)
					)
					(justify left bottom)
				)
			)
			(property "ki_keywords" "SMT, CERAMIC, OSCILLATOR"
				(at 0 0 0)
				(effects
					(font
						(size 1.27 1.27)
					)
					(hide yes)
				)
			)
			(symbol "Resonator_27MHz_ABM7_1_1"
				(polyline
					(pts
						(xy 2.54 1.27) (xy 2.54 -1.27)
					)
					(stroke
						(width 0.254)
						(type default)
					)
					(fill
						(type background)
					)
				)
				(rectangle
					(start 3.175 1.905)
					(end 4.445 -1.905)
					(stroke
						(width 0.254)
						(type default)
					)
					(fill
						(type background)
					)
				)
				(polyline
					(pts
						(xy 5.08 1.27) (xy 5.08 -1.27)
					)
					(stroke
						(width 0.254)
						(type default)
					)
					(fill
						(type background)
					)
				)
				(pin passive line
					(at 0 0 0)
					(length 2.54)
					(name "~"
						(effects
							(font
								(size 1.27 1.27)
							)
						)
					)
					(number "1"
						(effects
							(font
								(size 1.27 1.27)
							)
						)
					)
				)
				(pin passive line
					(at 7.62 0 180)
					(length 2.54)
					(name "~"
						(effects
							(font
								(size 1.27 1.27)
							)
						)
					)
					(number "2"
						(effects
							(font
								(size 1.27 1.27)
							)
						)
					)
				)
			)
		)
	(symbol "antmicroSlideSwitches:SW_CVS-02B"
			(exclude_from_sim no)
			(in_bom yes)
			(on_board yes)
			(property "Reference" "SW"
				(at 26.67 -2.54 0)
				(effects
					(font
						(size 1.27 1.27)
						(thickness 0.15)
					)
					(justify left bottom)
				)
			)
			(property "Value" "SW_CVS-02B"
				(at 26.67 -5.08 0)
				(effects
					(font
						(size 1.27 1.27)
						(thickness 0.15)
					)
					(justify left bottom)
					(hide yes)
				)
			)
			(property "Footprint" "antmicro-footprints:SW_DIP_SPSTx02_Slide_Copal_CVS-02xB_W5.9mm_P1mm"
				(at 26.67 -7.62 0)
				(effects
					(font
						(size 1.27 1.27)
						(thickness 0.15)
					)
					(justify left bottom)
					(hide yes)
				)
			)
			(property "Datasheet" "https://www.mouser.com/datasheet/2/972/cvs-1827291.pdf"
				(at 26.67 -10.16 0)
				(effects
					(font
						(size 1.27 1.27)
						(thickness 0.15)
					)
					(justify left bottom)
					(hide yes)
				)
			)
			(property "Description" "Slide switch, 2-position SMD Slide switch, 2-channel"
				(at 26.67 -22.86 0)
				(effects
					(font
						(size 1.27 1.27)
					)
					(justify left bottom)
					(hide yes)
				)
			)
			(property "MPN" "CVS-02B"
				(at 26.67 -12.7 0)
				(effects
					(font
						(size 1.27 1.27)
						(thickness 0.15)
					)
					(justify left bottom)
				)
			)
			(property "Manufacturer" "Nidec Components"
				(at 26.67 -15.24 0)
				(effects
					(font
						(size 1.27 1.27)
						(thickness 0.15)
					)
					(justify left bottom)
					(hide yes)
				)
			)
			(property "Author" "Antmicro"
				(at 26.67 -17.78 0)
				(effects
					(font
						(size 1.27 1.27)
						(thickness 0.15)
					)
					(justify left bottom)
					(hide yes)
				)
			)
			(property "License" "Apache-2.0"
				(at 26.67 -20.32 0)
				(effects
					(font
						(size 1.27 1.27)
						(thickness 0.15)
					)
					(justify left bottom)
					(hide yes)
				)
			)
			(property "ki_keywords" "HORIZONTAL, SMT, SWITCH, MECHANICAL"
				(at 0 0 0)
				(effects
					(font
						(size 1.27 1.27)
					)
					(hide yes)
				)
			)
			(property "ki_fp_filters" "SW?DIP?x2*"
				(at 0 0 0)
				(effects
					(font
						(size 1.27 1.27)
					)
					(hide yes)
				)
			)
			(symbol "SW_CVS-02B_1_1"
				(rectangle
					(start 2.54 2.54)
					(end 10.16 -7.62)
					(stroke
						(width 0.254)
						(type default)
					)
					(fill
						(type background)
					)
				)
				(polyline
					(pts
						(xy 3.81 0) (xy 2.54 0)
					)
					(stroke
						(width 0.254)
						(type default)
					)
					(fill
						(type none)
					)
				)
				(polyline
					(pts
						(xy 3.81 -2.54) (xy 2.54 -2.54)
					)
					(stroke
						(width 0.254)
						(type default)
					)
					(fill
						(type none)
					)
				)
				(circle
					(center 4.318 0)
					(radius 0.508)
					(stroke
						(width 0.254)
						(type default)
					)
					(fill
						(type none)
					)
				)
				(circle
					(center 4.318 -2.54)
					(radius 0.508)
					(stroke
						(width 0.254)
						(type default)
					)
					(fill
						(type none)
					)
				)
				(polyline
					(pts
						(xy 4.826 0.127) (xy 8.7122 1.1684)
					)
					(stroke
						(width 0.254)
						(type default)
					)
					(fill
						(type none)
					)
				)
				(polyline
					(pts
						(xy 4.826 -2.413) (xy 8.7122 -1.3716)
					)
					(stroke
						(width 0.254)
						(type default)
					)
					(fill
						(type none)
					)
				)
				(circle
					(center 8.382 0)
					(radius 0.508)
					(stroke
						(width 0.254)
						(type default)
					)
					(fill
						(type none)
					)
				)
				(circle
					(center 8.382 -2.54)
					(radius 0.508)
					(stroke
						(width 0.254)
						(type default)
					)
					(fill
						(type none)
					)
				)
				(polyline
					(pts
						(xy 10.16 0) (xy 8.89 0)
					)
					(stroke
						(width 0.254)
						(type default)
					)
					(fill
						(type none)
					)
				)
				(polyline
					(pts
						(xy 10.16 -2.54) (xy 8.89 -2.54)
					)
					(stroke
						(width 0.254)
						(type default)
					)
					(fill
						(type none)
					)
				)
				(pin passive line
					(at 0 0 0)
					(length 2.54)
					(name "~"
						(effects
							(font
								(size 1.27 1.27)
							)
						)
					)
					(number "1"
						(effects
							(font
								(size 1.27 1.27)
							)
						)
					)
				)
				(pin passive line
					(at 0 -2.54 0)
					(length 2.54)
					(name "~"
						(effects
							(font
								(size 1.27 1.27)
							)
						)
					)
					(number "2"
						(effects
							(font
								(size 1.27 1.27)
							)
						)
					)
				)
				(pin passive line
					(at 12.7 0 180)
					(length 2.54)
					(name "~"
						(effects
							(font
								(size 1.27 1.27)
							)
						)
					)
					(number "4"
						(effects
							(font
								(size 1.27 1.27)
							)
						)
					)
				)
				(pin passive line
					(at 12.7 -2.54 180)
					(length 2.54)
					(name "~"
						(effects
							(font
								(size 1.27 1.27)
							)
						)
					)
					(number "3"
						(effects
							(font
								(size 1.27 1.27)
							)
						)
					)
				)
				(pin power_in line
					(at 12.7 -5.08 180)
					(length 2.54)
					(name "SH"
						(effects
							(font
								(size 1.27 1.27)
							)
						)
					)
					(number "SH"
						(effects
							(font
								(size 1.27 1.27)
							)
						)
					)
				)
			)
		)
	(symbol "antmicroTestPoints:TP_0.75mm_SMD"
			(pin_names
				(hide yes)
			)
			(exclude_from_sim no)
			(in_bom no)
			(on_board yes)
			(property "Reference" "TP"
				(at 10.16 -1.27 0)
				(effects
					(font
						(size 1.27 1.27)
						(thickness 0.15)
					)
					(justify left bottom)
				)
			)
			(property "Value" "TP_0.75mm_SMD"
				(at 10.16 -3.81 0)
				(effects
					(font
						(size 1.27 1.27)
						(thickness 0.15)
					)
					(justify left bottom)
					(hide yes)
				)
			)
			(property "Footprint" "antmicro-footprints:TP_SMD_0.75mm"
				(at 10.16 -6.35 0)
				(effects
					(font
						(size 1.27 1.27)
						(thickness 0.15)
					)
					(justify left bottom)
					(hide yes)
				)
			)
			(property "Datasheet" ""
				(at 17.78 -12.7 0)
				(effects
					(font
						(size 1.27 1.27)
						(thickness 0.15)
					)
					(justify left bottom)
					(hide yes)
				)
			)
			(property "Description" "SMT test point"
				(at 10.795 -13.97 0)
				(effects
					(font
						(size 1.27 1.27)
					)
					(justify left bottom)
					(hide yes)
				)
			)
			(property "MPN" ""
				(at 10.795 -11.43 0)
				(effects
					(font
						(size 1.27 1.27)
						(thickness 0.15)
					)
					(justify left bottom)
					(hide yes)
				)
			)
			(property "Manufacturer" ""
				(at 10.795 -6.35 0)
				(effects
					(font
						(size 1.27 1.27)
						(thickness 0.15)
					)
					(justify left bottom)
					(hide yes)
				)
			)
			(property "Author" "Antmicro"
				(at 10.16 -8.89 0)
				(effects
					(font
						(size 1.27 1.27)
						(thickness 0.15)
					)
					(justify left bottom)
					(hide yes)
				)
			)
			(property "License" "Apache-2.0"
				(at 10.16 -11.43 0)
				(effects
					(font
						(size 1.27 1.27)
						(thickness 0.15)
					)
					(justify left bottom)
					(hide yes)
				)
			)
			(property "ki_keywords" "TESTPOINT"
				(at 0 0 0)
				(effects
					(font
						(size 1.27 1.27)
					)
					(hide yes)
				)
			)
			(symbol "TP_0.75mm_SMD_1_1"
				(circle
					(center 3.175 0)
					(radius 0.635)
					(stroke
						(width 0.254)
						(type default)
					)
					(fill
						(type none)
					)
				)
				(pin passive line
					(at 0 0 0)
					(length 2.54)
					(name "1"
						(effects
							(font
								(size 1.27 1.27)
							)
						)
					)
					(number "1"
						(effects
							(font
								(size 1.27 1.27)
							)
						)
					)
				)
			)
		)
	(symbol "antmicroTransistorsBipolarArrays:BCM857BS-7-F"
			(exclude_from_sim no)
			(in_bom yes)
			(on_board yes)
			(property "Reference" "Q"
				(at 22.86 0 0)
				(effects
					(font
						(size 1.27 1.27)
						(thickness 0.15)
					)
					(justify left bottom)
				)
			)
			(property "Value" "BCM857BS-7-F"
				(at 22.86 -2.54 0)
				(effects
					(font
						(size 1.27 1.27)
						(thickness 0.15)
					)
					(justify left bottom)
					(hide yes)
				)
			)
			(property "Footprint" "antmicro-footprints:SOT-363"
				(at 22.86 -5.08 0)
				(effects
					(font
						(size 1.27 1.27)
						(thickness 0.15)
					)
					(justify left bottom)
					(hide yes)
				)
			)
			(property "Datasheet" "https://www.diodes.com/assets/Datasheets/BCM857BS.pdf"
				(at 22.86 -7.62 0)
				(effects
					(font
						(size 1.27 1.27)
						(thickness 0.15)
					)
					(justify left bottom)
					(hide yes)
				)
			)
			(property "Description" "Bipolar (BJT) Transistor Array, 2 Transistors, PNP, 45V, 100mA, SOT-363, Surface Mount"
				(at 22.86 -20.32 0)
				(effects
					(font
						(size 1.27 1.27)
					)
					(justify left bottom)
					(hide yes)
				)
			)
			(property "MPN" "BCM857BS-7-F"
				(at 22.86 -10.16 0)
				(effects
					(font
						(size 1.27 1.27)
						(thickness 0.15)
					)
					(justify left bottom)
				)
			)
			(property "Manufacturer" "Diodes Incorporated"
				(at 22.86 -12.7 0)
				(effects
					(font
						(size 1.27 1.27)
						(thickness 0.15)
					)
					(justify left bottom)
					(hide yes)
				)
			)
			(property "Author" "Antmicro"
				(at 22.86 -15.24 0)
				(effects
					(font
						(size 1.27 1.27)
						(thickness 0.15)
					)
					(justify left bottom)
					(hide yes)
				)
			)
			(property "License" "Apache-2.0"
				(at 22.86 -17.78 0)
				(effects
					(font
						(size 1.27 1.27)
						(thickness 0.15)
					)
					(justify left bottom)
					(hide yes)
				)
			)
			(property "ki_keywords" "SMT, TRANSISTOR, SEMICONDUCTOR, BIPOLAR"
				(at 0 0 0)
				(effects
					(font
						(size 1.27 1.27)
					)
					(hide yes)
				)
			)
			(symbol "BCM857BS-7-F_1_1"
				(rectangle
					(start 2.54 3.81)
					(end 15.24 -3.81)
					(stroke
						(width 0.254)
						(type default)
					)
					(fill
						(type background)
					)
				)
				(polyline
					(pts
						(xy 2.54 0) (xy 4.445 0)
					)
					(stroke
						(width 0.254)
						(type default)
					)
					(fill
						(type none)
					)
				)
				(polyline
					(pts
						(xy 4.445 1.905) (xy 4.445 -1.905) (xy 4.445 -1.905)
					)
					(stroke
						(width 0.254)
						(type default)
					)
					(fill
						(type background)
					)
				)
				(polyline
					(pts
						(xy 4.445 0.635) (xy 6.35 2.54)
					)
					(stroke
						(width 0.254)
						(type default)
					)
					(fill
						(type background)
					)
				)
				(polyline
					(pts
						(xy 4.445 -0.635) (xy 6.35 -2.54) (xy 6.35 -2.54)
					)
					(stroke
						(width 0.254)
						(type default)
					)
					(fill
						(type background)
					)
				)
				(polyline
					(pts
						(xy 4.445 -0.635) (xy 6.35 -2.54) (xy 6.35 -2.54)
					)
					(stroke
						(width 0.254)
						(type default)
					)
					(fill
						(type background)
					)
				)
				(polyline
					(pts
						(xy 5.207 -1.8796) (xy 5.715 -1.3716) (xy 4.699 -0.8636) (xy 5.207 -1.8796) (xy 5.207 -1.8796)
					)
					(stroke
						(width 0.254)
						(type default)
					)
					(fill
						(type outline)
					)
				)
				(polyline
					(pts
						(xy 5.207 -1.8796) (xy 5.715 -1.3716) (xy 4.699 -0.8636) (xy 5.207 -1.8796) (xy 5.207 -1.8796)
					)
					(stroke
						(width 0.254)
						(type default)
					)
					(fill
						(type background)
					)
				)
				(polyline
					(pts
						(xy 5.207 -1.8796) (xy 5.715 -1.3716) (xy 4.699 -0.8636) (xy 5.207 -1.8796) (xy 5.207 -1.8796)
					)
					(stroke
						(width 0.254)
						(type default)
					)
					(fill
						(type background)
					)
				)
				(polyline
					(pts
						(xy 5.207 -1.8796) (xy 5.715 -1.3716) (xy 4.699 -0.8636) (xy 5.207 -1.8796) (xy 5.207 -1.8796)
					)
					(stroke
						(width 0.254)
						(type default)
					)
					(fill
						(type background)
					)
				)
				(polyline
					(pts
						(xy 6.35 2.54) (xy 6.35 3.81)
					)
					(stroke
						(width 0.254)
						(type default)
					)
					(fill
						(type none)
					)
				)
				(polyline
					(pts
						(xy 6.35 -2.54) (xy 6.35 -3.81)
					)
					(stroke
						(width 0.254)
						(type default)
					)
					(fill
						(type none)
					)
				)
				(polyline
					(pts
						(xy 11.43 2.54) (xy 11.43 3.81)
					)
					(stroke
						(width 0.254)
						(type default)
					)
					(fill
						(type none)
					)
				)
				(polyline
					(pts
						(xy 11.43 -2.54) (xy 11.43 -3.81)
					)
					(stroke
						(width 0.254)
						(type default)
					)
					(fill
						(type none)
					)
				)
				(polyline
					(pts
						(xy 12.573 -1.8796) (xy 12.065 -1.3716) (xy 13.081 -0.8636) (xy 12.573 -1.8796) (xy 12.573 -1.8796)
					)
					(stroke
						(width 0.254)
						(type default)
					)
					(fill
						(type outline)
					)
				)
				(polyline
					(pts
						(xy 12.573 -1.8796) (xy 12.065 -1.3716) (xy 13.081 -0.8636) (xy 12.573 -1.8796) (xy 12.573 -1.8796)
					)
					(stroke
						(width 0.254)
						(type default)
					)
					(fill
						(type background)
					)
				)
				(polyline
					(pts
						(xy 12.573 -1.8796) (xy 12.065 -1.3716) (xy 13.081 -0.8636) (xy 12.573 -1.8796) (xy 12.573 -1.8796)
					)
					(stroke
						(width 0.254)
						(type default)
					)
					(fill
						(type background)
					)
				)
				(polyline
					(pts
						(xy 12.573 -1.8796) (xy 12.065 -1.3716) (xy 13.081 -0.8636) (xy 12.573 -1.8796) (xy 12.573 -1.8796)
					)
					(stroke
						(width 0.254)
						(type default)
					)
					(fill
						(type background)
					)
				)
				(polyline
					(pts
						(xy 13.335 1.905) (xy 13.335 -1.905) (xy 13.335 -1.905)
					)
					(stroke
						(width 0.254)
						(type default)
					)
					(fill
						(type background)
					)
				)
				(polyline
					(pts
						(xy 13.335 0.635) (xy 11.43 2.54)
					)
					(stroke
						(width 0.254)
						(type default)
					)
					(fill
						(type background)
					)
				)
				(polyline
					(pts
						(xy 13.335 0) (xy 15.24 0)
					)
					(stroke
						(width 0.254)
						(type default)
					)
					(fill
						(type none)
					)
				)
				(polyline
					(pts
						(xy 13.335 -0.635) (xy 11.43 -2.54) (xy 11.43 -2.54)
					)
					(stroke
						(width 0.254)
						(type default)
					)
					(fill
						(type background)
					)
				)
				(polyline
					(pts
						(xy 13.335 -0.635) (xy 11.43 -2.54) (xy 11.43 -2.54)
					)
					(stroke
						(width 0.254)
						(type default)
					)
					(fill
						(type background)
					)
				)
				(pin input line
					(at 0 0 0)
					(length 2.54)
					(name "~"
						(effects
							(font
								(size 1.27 1.27)
							)
						)
					)
					(number "2"
						(effects
							(font
								(size 1.27 1.27)
							)
						)
					)
				)
				(pin passive line
					(at 6.35 6.35 270)
					(length 2.54)
					(name "~"
						(effects
							(font
								(size 1.27 1.27)
							)
						)
					)
					(number "6"
						(effects
							(font
								(size 1.27 1.27)
							)
						)
					)
				)
				(pin passive line
					(at 6.35 -6.35 90)
					(length 2.54)
					(name "~"
						(effects
							(font
								(size 1.27 1.27)
							)
						)
					)
					(number "1"
						(effects
							(font
								(size 1.27 1.27)
							)
						)
					)
				)
				(pin passive line
					(at 11.43 6.35 270)
					(length 2.54)
					(name "~"
						(effects
							(font
								(size 1.27 1.27)
							)
						)
					)
					(number "3"
						(effects
							(font
								(size 1.27 1.27)
							)
						)
					)
				)
				(pin passive line
					(at 11.43 -6.35 90)
					(length 2.54)
					(name "~"
						(effects
							(font
								(size 1.27 1.27)
							)
						)
					)
					(number "4"
						(effects
							(font
								(size 1.27 1.27)
							)
						)
					)
				)
				(pin input line
					(at 17.78 0 180)
					(length 2.54)
					(name "~"
						(effects
							(font
								(size 1.27 1.27)
							)
						)
					)
					(number "5"
						(effects
							(font
								(size 1.27 1.27)
							)
						)
					)
				)
			)
		)
	(symbol "antmicroTransistorsFETsMOSFETsSingle:2N7002_SOT-23-3"
			(pin_names
				(offset 0)
			)
			(exclude_from_sim no)
			(in_bom yes)
			(on_board yes)
			(property "Reference" "Q"
				(at 22.86 -5.08 0)
				(effects
					(font
						(size 1.27 1.27)
						(thickness 0.15)
					)
					(justify left bottom)
				)
			)
			(property "Value" "2N7002_SOT-23-3"
				(at 22.86 -7.62 0)
				(effects
					(font
						(size 1.27 1.27)
						(thickness 0.15)
					)
					(justify left bottom)
					(hide yes)
				)
			)
			(property "Footprint" "antmicro-footprints:SOT-23-3"
				(at 22.86 -10.16 0)
				(effects
					(font
						(size 1.27 1.27)
						(thickness 0.15)
					)
					(justify left bottom)
					(hide yes)
				)
			)
			(property "Datasheet" "https://www.onsemi.com/pub/Collateral/NDS7002A-D.PDF"
				(at 22.86 -12.7 0)
				(effects
					(font
						(size 1.27 1.27)
						(thickness 0.15)
					)
					(justify left bottom)
					(hide yes)
				)
			)
			(property "Description" "Power MOSFET, N Channel, 60 V, 115 mA, 1.2 ohm, SOT-23, Surface Mount"
				(at 22.86 -25.4 0)
				(effects
					(font
						(size 1.27 1.27)
					)
					(justify left bottom)
					(hide yes)
				)
			)
			(property "MPN" "2N7002"
				(at 22.86 -15.24 0)
				(effects
					(font
						(size 1.27 1.27)
						(thickness 0.15)
					)
					(justify left bottom)
				)
			)
			(property "Manufacturer" "ON Semiconductor"
				(at 22.86 -17.78 0)
				(effects
					(font
						(size 1.27 1.27)
						(thickness 0.15)
					)
					(justify left bottom)
					(hide yes)
				)
			)
			(property "Author" "Antmicro"
				(at 22.86 -20.32 0)
				(effects
					(font
						(size 1.27 1.27)
						(thickness 0.15)
					)
					(justify left bottom)
					(hide yes)
				)
			)
			(property "License" "Apache-2.0"
				(at 22.86 -22.86 0)
				(effects
					(font
						(size 1.27 1.27)
						(thickness 0.15)
					)
					(justify left bottom)
					(hide yes)
				)
			)
			(property "ki_keywords" "SMT, TRANSISTOR, SEMICONDUCTOR, NMOS"
				(at 0 0 0)
				(effects
					(font
						(size 1.27 1.27)
					)
					(hide yes)
				)
			)
			(symbol "2N7002_SOT-23-3_1_1"
				(polyline
					(pts
						(xy 2.54 0) (xy 4.572 0) (xy 4.572 3.937)
					)
					(stroke
						(width 0.254)
						(type default)
					)
					(fill
						(type none)
					)
				)
				(polyline
					(pts
						(xy 5.08 4.445) (xy 5.08 3.429)
					)
					(stroke
						(width 0.254)
						(type default)
					)
					(fill
						(type background)
					)
				)
				(polyline
					(pts
						(xy 5.08 2.54) (xy 5.08 3.048)
					)
					(stroke
						(width 0.254)
						(type default)
					)
					(fill
						(type background)
					)
				)
				(polyline
					(pts
						(xy 5.08 2.54) (xy 5.08 2.032)
					)
					(stroke
						(width 0.254)
						(type default)
					)
					(fill
						(type background)
					)
				)
				(polyline
					(pts
						(xy 5.08 2.54) (xy 5.842 3.048) (xy 5.842 2.032) (xy 5.08 2.54)
					)
					(stroke
						(width 0.254)
						(type default)
					)
					(fill
						(type outline)
					)
				)
				(polyline
					(pts
						(xy 5.08 1.143) (xy 5.08 1.651)
					)
					(stroke
						(width 0.254)
						(type default)
					)
					(fill
						(type background)
					)
				)
				(polyline
					(pts
						(xy 5.08 1.143) (xy 5.08 0.635)
					)
					(stroke
						(width 0.254)
						(type default)
					)
					(fill
						(type background)
					)
				)
				(circle
					(center 6.35 2.54)
					(radius 3.302)
					(stroke
						(width 0.254)
						(type default)
					)
					(fill
						(type background)
					)
				)
				(polyline
					(pts
						(xy 7.493 0.635) (xy 8.636 0.635) (xy 8.636 3.937) (xy 8.636 4.445) (xy 7.493 4.445)
					)
					(stroke
						(width 0.254)
						(type default)
					)
					(fill
						(type background)
					)
				)
				(polyline
					(pts
						(xy 7.62 6.35) (xy 7.62 3.937) (xy 5.08 3.937)
					)
					(stroke
						(width 0.254)
						(type default)
					)
					(fill
						(type none)
					)
				)
				(circle
					(center 7.62 4.445)
					(radius 0.127)
					(stroke
						(width 0.254)
						(type default)
					)
					(fill
						(type background)
					)
				)
				(polyline
					(pts
						(xy 7.62 1.143) (xy 5.08 1.143)
					)
					(stroke
						(width 0.254)
						(type default)
					)
					(fill
						(type background)
					)
				)
				(circle
					(center 7.62 1.143)
					(radius 0.127)
					(stroke
						(width 0.254)
						(type default)
					)
					(fill
						(type background)
					)
				)
				(circle
					(center 7.62 0.635)
					(radius 0.127)
					(stroke
						(width 0.254)
						(type default)
					)
					(fill
						(type background)
					)
				)
				(polyline
					(pts
						(xy 7.62 -1.27) (xy 7.62 2.54) (xy 5.08 2.54)
					)
					(stroke
						(width 0.254)
						(type default)
					)
					(fill
						(type none)
					)
				)
				(polyline
					(pts
						(xy 8.636 3.048) (xy 8.128 2.286) (xy 9.144 2.286) (xy 8.636 3.048)
					)
					(stroke
						(width 0.254)
						(type default)
					)
					(fill
						(type outline)
					)
				)
				(polyline
					(pts
						(xy 9.144 3.048) (xy 8.128 3.048)
					)
					(stroke
						(width 0.254)
						(type default)
					)
					(fill
						(type background)
					)
				)
				(pin input line
					(at 0 0 0)
					(length 2.54)
					(name "G"
						(effects
							(font
								(size 1.27 1.27)
							)
						)
					)
					(number "1"
						(effects
							(font
								(size 1.27 1.27)
							)
						)
					)
				)
				(pin passive line
					(at 7.62 8.89 270)
					(length 2.54)
					(name "D"
						(effects
							(font
								(size 1.27 1.27)
							)
						)
					)
					(number "3"
						(effects
							(font
								(size 1.27 1.27)
							)
						)
					)
				)
				(pin passive line
					(at 7.62 -3.81 90)
					(length 2.54)
					(name "S"
						(effects
							(font
								(size 1.27 1.27)
							)
						)
					)
					(number "2"
						(effects
							(font
								(size 1.27 1.27)
							)
						)
					)
				)
			)
		)
	(symbol "antmicroTransistorsFETsMOSFETsSingle:AO3401A"
			(pin_names
				(offset 0)
			)
			(exclude_from_sim no)
			(in_bom yes)
			(on_board yes)
			(property "Reference" "Q"
				(at 22.86 -6.35 0)
				(effects
					(font
						(size 1.27 1.27)
						(thickness 0.15)
					)
					(justify left bottom)
				)
			)
			(property "Value" "AO3401A"
				(at 22.86 -8.89 0)
				(effects
					(font
						(size 1.27 1.27)
						(thickness 0.15)
					)
					(justify left bottom)
					(hide yes)
				)
			)
			(property "Footprint" "antmicro-footprints:SOT-23-3"
				(at 22.86 -11.43 0)
				(effects
					(font
						(size 1.27 1.27)
						(thickness 0.15)
					)
					(justify left bottom)
					(hide yes)
				)
			)
			(property "Datasheet" "http://aosmd.com/res/data_sheets/AO3401A.pdf"
				(at 22.86 -13.97 0)
				(effects
					(font
						(size 1.27 1.27)
						(thickness 0.15)
					)
					(justify left bottom)
					(hide yes)
				)
			)
			(property "Description" "Power MOSFET, P Channel, 30 V, 4 A, 0.07 ohm, SOT-23, Surface Mount"
				(at 22.86 -26.67 0)
				(effects
					(font
						(size 1.27 1.27)
					)
					(justify left bottom)
					(hide yes)
				)
			)
			(property "MPN" "AO3401A"
				(at 22.86 -16.51 0)
				(effects
					(font
						(size 1.27 1.27)
						(thickness 0.15)
					)
					(justify left bottom)
				)
			)
			(property "Manufacturer" "AOSMD"
				(at 22.86 -19.05 0)
				(effects
					(font
						(size 1.27 1.27)
						(thickness 0.15)
					)
					(justify left bottom)
					(hide yes)
				)
			)
			(property "Author" "Antmicro"
				(at 22.86 -21.59 0)
				(effects
					(font
						(size 1.27 1.27)
						(thickness 0.15)
					)
					(justify left bottom)
					(hide yes)
				)
			)
			(property "License" "Apache-2.0"
				(at 22.86 -24.13 0)
				(effects
					(font
						(size 1.27 1.27)
						(thickness 0.15)
					)
					(justify left bottom)
					(hide yes)
				)
			)
			(property "ki_keywords" "SMT, TRANSISTOR, SEMICONDUCTOR"
				(at 0 0 0)
				(effects
					(font
						(size 1.27 1.27)
					)
					(hide yes)
				)
			)
			(symbol "AO3401A_1_1"
				(polyline
					(pts
						(xy 2.54 0) (xy 4.572 0) (xy 4.572 3.937)
					)
					(stroke
						(width 0.254)
						(type default)
					)
					(fill
						(type none)
					)
				)
				(polyline
					(pts
						(xy 5.08 4.445) (xy 5.08 3.429)
					)
					(stroke
						(width 0.254)
						(type default)
					)
					(fill
						(type background)
					)
				)
				(polyline
					(pts
						(xy 5.08 2.54) (xy 5.08 3.048)
					)
					(stroke
						(width 0.254)
						(type default)
					)
					(fill
						(type background)
					)
				)
				(polyline
					(pts
						(xy 5.08 2.54) (xy 5.08 2.032)
					)
					(stroke
						(width 0.254)
						(type default)
					)
					(fill
						(type background)
					)
				)
				(polyline
					(pts
						(xy 5.08 1.143) (xy 5.08 1.651)
					)
					(stroke
						(width 0.254)
						(type default)
					)
					(fill
						(type background)
					)
				)
				(polyline
					(pts
						(xy 5.08 1.143) (xy 5.08 0.635)
					)
					(stroke
						(width 0.254)
						(type default)
					)
					(fill
						(type background)
					)
				)
				(circle
					(center 6.35 2.54)
					(radius 3.302)
					(stroke
						(width 0.254)
						(type default)
					)
					(fill
						(type background)
					)
				)
				(polyline
					(pts
						(xy 7.239 2.54) (xy 6.477 3.048) (xy 6.477 2.032) (xy 7.239 2.54)
					)
					(stroke
						(width 0.254)
						(type default)
					)
					(fill
						(type outline)
					)
				)
				(polyline
					(pts
						(xy 7.493 0.635) (xy 8.636 0.635) (xy 8.636 3.937) (xy 8.636 4.445) (xy 7.493 4.445)
					)
					(stroke
						(width 0.254)
						(type default)
					)
					(fill
						(type background)
					)
				)
				(polyline
					(pts
						(xy 7.62 6.35) (xy 7.62 3.937) (xy 5.08 3.937)
					)
					(stroke
						(width 0.254)
						(type default)
					)
					(fill
						(type none)
					)
				)
				(circle
					(center 7.62 4.445)
					(radius 0.127)
					(stroke
						(width 0.254)
						(type default)
					)
					(fill
						(type background)
					)
				)
				(polyline
					(pts
						(xy 7.62 1.143) (xy 5.08 1.143)
					)
					(stroke
						(width 0.254)
						(type default)
					)
					(fill
						(type background)
					)
				)
				(circle
					(center 7.62 1.143)
					(radius 0.127)
					(stroke
						(width 0.254)
						(type default)
					)
					(fill
						(type background)
					)
				)
				(circle
					(center 7.62 0.635)
					(radius 0.127)
					(stroke
						(width 0.254)
						(type default)
					)
					(fill
						(type background)
					)
				)
				(polyline
					(pts
						(xy 7.62 -1.27) (xy 7.62 2.54) (xy 5.08 2.54)
					)
					(stroke
						(width 0.254)
						(type default)
					)
					(fill
						(type none)
					)
				)
				(polyline
					(pts
						(xy 8.636 2.286) (xy 8.128 3.048) (xy 9.144 3.048) (xy 8.636 2.286)
					)
					(stroke
						(width 0.254)
						(type default)
					)
					(fill
						(type outline)
					)
				)
				(polyline
					(pts
						(xy 9.144 2.2352) (xy 8.128 2.2352)
					)
					(stroke
						(width 0.254)
						(type default)
					)
					(fill
						(type background)
					)
				)
				(pin input line
					(at 0 0 0)
					(length 2.54)
					(name "G"
						(effects
							(font
								(size 1.27 1.27)
							)
						)
					)
					(number "1"
						(effects
							(font
								(size 1.27 1.27)
							)
						)
					)
				)
				(pin passive line
					(at 7.62 8.89 270)
					(length 2.54)
					(name "D"
						(effects
							(font
								(size 1.27 1.27)
							)
						)
					)
					(number "3"
						(effects
							(font
								(size 1.27 1.27)
							)
						)
					)
				)
				(pin passive line
					(at 7.62 -3.81 90)
					(length 2.54)
					(name "S"
						(effects
							(font
								(size 1.27 1.27)
							)
						)
					)
					(number "2"
						(effects
							(font
								(size 1.27 1.27)
							)
						)
					)
				)
			)
		)
	(symbol "antmicroUSBConnectors:USB-C_GCT_USB4105-GF-A"
			(exclude_from_sim no)
			(in_bom yes)
			(on_board yes)
			(property "Reference" "J"
				(at 38.1 -2.54 0)
				(effects
					(font
						(size 1.27 1.27)
						(thickness 0.15)
					)
					(justify left bottom)
				)
			)
			(property "Value" "USB-C_GCT_USB4105-GF-A"
				(at 38.1 -5.08 0)
				(effects
					(font
						(size 1.27 1.27)
						(thickness 0.15)
					)
					(justify left bottom)
					(hide yes)
				)
			)
			(property "Footprint" "antmicro-footprints:USB-C_Receptacle_GCT_USB4105-GF-A"
				(at 38.1 -7.62 0)
				(effects
					(font
						(size 1.27 1.27)
						(thickness 0.15)
					)
					(justify left bottom)
					(hide yes)
				)
			)
			(property "Datasheet" "https://gct.co/files/drawings/usb4105.pdf"
				(at 38.1 -10.16 0)
				(effects
					(font
						(size 1.27 1.27)
						(thickness 0.15)
					)
					(justify left bottom)
					(hide yes)
				)
			)
			(property "Description" "USB-C (USB TYPE-C) USB 2.0 Receptacle Connector 24 (16+8 Dummy) Position Surface Mount, Right Angle"
				(at 38.1 -22.86 0)
				(effects
					(font
						(size 1.27 1.27)
					)
					(justify left bottom)
					(hide yes)
				)
			)
			(property "Manufacturer" "GCT"
				(at 38.1 -12.7 0)
				(effects
					(font
						(size 1.27 1.27)
						(thickness 0.15)
					)
					(justify left bottom)
					(hide yes)
				)
			)
			(property "MPN" "USB4105-GF-A"
				(at 38.1 -15.24 0)
				(effects
					(font
						(size 1.27 1.27)
						(thickness 0.15)
					)
					(justify left bottom)
				)
			)
			(property "Author" "Antmicro"
				(at 38.1 -17.78 0)
				(effects
					(font
						(size 1.27 1.27)
						(thickness 0.15)
					)
					(justify left bottom)
					(hide yes)
				)
			)
			(property "License" "Apache-2.0"
				(at 38.1 -20.32 0)
				(effects
					(font
						(size 1.27 1.27)
						(thickness 0.15)
					)
					(justify left bottom)
					(hide yes)
				)
			)
			(property "ki_keywords" "USB, CONNECTOR, SMT, HORIZONTAL"
				(at 0 0 0)
				(effects
					(font
						(size 1.27 1.27)
					)
					(hide yes)
				)
			)
			(symbol "USB-C_GCT_USB4105-GF-A_1_1"
				(rectangle
					(start -22.86 2.54)
					(end -3.81 -38.1)
					(stroke
						(width 0.254)
						(type default)
					)
					(fill
						(type background)
					)
				)
				(circle
					(center -20.066 -18.034)
					(radius 0.284)
					(stroke
						(width 0.254)
						(type default)
					)
					(fill
						(type outline)
					)
				)
				(polyline
					(pts
						(xy -19.812 -16.383) (xy -19.177 -15.24) (xy -18.542 -16.383) (xy -19.812 -16.383)
					)
					(stroke
						(width 0.254)
						(type default)
					)
					(fill
						(type outline)
					)
				)
				(polyline
					(pts
						(xy -19.177 -19.558) (xy -18.288 -18.669) (xy -18.288 -18.034)
					)
					(stroke
						(width 0.254)
						(type default)
					)
					(fill
						(type background)
					)
				)
				(polyline
					(pts
						(xy -19.177 -19.939) (xy -20.066 -19.05) (xy -20.066 -18.415)
					)
					(stroke
						(width 0.254)
						(type default)
					)
					(fill
						(type background)
					)
				)
				(polyline
					(pts
						(xy -19.177 -20.701) (xy -19.177 -16.383)
					)
					(stroke
						(width 0.254)
						(type default)
					)
					(fill
						(type background)
					)
				)
				(circle
					(center -19.177 -20.828)
					(radius 0.5236)
					(stroke
						(width 0.254)
						(type default)
					)
					(fill
						(type outline)
					)
				)
				(rectangle
					(start -18.669 -18.034)
					(end -17.907 -17.272)
					(stroke
						(width 0.254)
						(type default)
					)
					(fill
						(type outline)
					)
				)
				(polyline
					(pts
						(xy -16.51 -21.59) (xy -16.51 -13.97)
					)
					(stroke
						(width 0.254)
						(type default)
					)
					(fill
						(type background)
					)
				)
				(rectangle
					(start -15.24 -21.59)
					(end -13.97 -13.97)
					(stroke
						(width 0.254)
						(type default)
					)
					(fill
						(type outline)
					)
				)
				(arc
					(start -15.24 -13.97)
					(mid -14.605 -13.3377)
					(end -13.97 -13.97)
					(stroke
						(width 0.254)
						(type default)
					)
					(fill
						(type outline)
					)
				)
				(arc
					(start -15.24 -13.97)
					(mid -14.605 -13.3377)
					(end -13.97 -13.97)
					(stroke
						(width 0.254)
						(type default)
					)
					(fill
						(type background)
					)
				)
				(arc
					(start -16.51 -13.97)
					(mid -14.605 -12.0733)
					(end -12.7 -13.97)
					(stroke
						(width 0.254)
						(type default)
					)
					(fill
						(type background)
					)
				)
				(arc
					(start -12.7 -21.59)
					(mid -14.605 -23.4867)
					(end -16.51 -21.59)
					(stroke
						(width 0.254)
						(type default)
					)
					(fill
						(type background)
					)
				)
				(arc
					(start -13.97 -21.59)
					(mid -14.605 -22.2223)
					(end -15.24 -21.59)
					(stroke
						(width 0.254)
						(type default)
					)
					(fill
						(type outline)
					)
				)
				(arc
					(start -13.97 -21.59)
					(mid -14.605 -22.2223)
					(end -15.24 -21.59)
					(stroke
						(width 0.254)
						(type default)
					)
					(fill
						(type background)
					)
				)
				(polyline
					(pts
						(xy -12.7 -13.97) (xy -12.7 -21.59)
					)
					(stroke
						(width 0.254)
						(type default)
					)
					(fill
						(type background)
					)
				)
				(pin power_in line
					(at 0 0 180)
					(length 3.81)
					(name "VBUS"
						(effects
							(font
								(size 1.27 1.27)
							)
						)
					)
					(number "A4"
						(effects
							(font
								(size 1.27 1.27)
							)
						)
					)
				)
				(pin passive line
					(at 0 0 180)
					(length 3.81)
					(hide yes)
					(name "VBUS"
						(effects
							(font
								(size 1.27 1.27)
							)
						)
					)
					(number "A9"
						(effects
							(font
								(size 1.27 1.27)
							)
						)
					)
				)
				(pin passive line
					(at 0 0 180)
					(length 3.81)
					(hide yes)
					(name "VBUS"
						(effects
							(font
								(size 1.27 1.27)
							)
						)
					)
					(number "B4"
						(effects
							(font
								(size 1.27 1.27)
							)
						)
					)
				)
				(pin passive line
					(at 0 0 180)
					(length 3.81)
					(hide yes)
					(name "VBUS"
						(effects
							(font
								(size 1.27 1.27)
							)
						)
					)
					(number "B9"
						(effects
							(font
								(size 1.27 1.27)
							)
						)
					)
				)
				(pin bidirectional line
					(at 0 -5.08 180)
					(length 3.81)
					(name "CC_{1}"
						(effects
							(font
								(size 1.27 1.27)
							)
						)
					)
					(number "A5"
						(effects
							(font
								(size 1.27 1.27)
							)
						)
					)
				)
				(pin bidirectional line
					(at 0 -7.62 180)
					(length 3.81)
					(name "CC_{2}"
						(effects
							(font
								(size 1.27 1.27)
							)
						)
					)
					(number "B5"
						(effects
							(font
								(size 1.27 1.27)
							)
						)
					)
				)
				(pin bidirectional line
					(at 0 -12.7 180)
					(length 3.81)
					(name "D_{A}+"
						(effects
							(font
								(size 1.27 1.27)
							)
						)
					)
					(number "A6"
						(effects
							(font
								(size 1.27 1.27)
							)
						)
					)
				)
				(pin bidirectional line
					(at 0 -15.24 180)
					(length 3.81)
					(name "D_{A}-"
						(effects
							(font
								(size 1.27 1.27)
							)
						)
					)
					(number "A7"
						(effects
							(font
								(size 1.27 1.27)
							)
						)
					)
				)
				(pin bidirectional line
					(at 0 -17.78 180)
					(length 3.81)
					(name "D_{B}+"
						(effects
							(font
								(size 1.27 1.27)
							)
						)
					)
					(number "B6"
						(effects
							(font
								(size 1.27 1.27)
							)
						)
					)
				)
				(pin bidirectional line
					(at 0 -20.32 180)
					(length 3.81)
					(name "D_{B}-"
						(effects
							(font
								(size 1.27 1.27)
							)
						)
					)
					(number "B7"
						(effects
							(font
								(size 1.27 1.27)
							)
						)
					)
				)
				(pin bidirectional line
					(at 0 -25.4 180)
					(length 3.81)
					(name "SBU_{1}"
						(effects
							(font
								(size 1.27 1.27)
							)
						)
					)
					(number "A8"
						(effects
							(font
								(size 1.27 1.27)
							)
						)
					)
				)
				(pin bidirectional line
					(at 0 -27.94 180)
					(length 3.81)
					(name "SBU_{2}"
						(effects
							(font
								(size 1.27 1.27)
							)
						)
					)
					(number "B8"
						(effects
							(font
								(size 1.27 1.27)
							)
						)
					)
				)
				(pin power_in line
					(at 0 -33.02 180)
					(length 3.81)
					(name "GND"
						(effects
							(font
								(size 1.27 1.27)
							)
						)
					)
					(number "A1"
						(effects
							(font
								(size 1.27 1.27)
							)
						)
					)
				)
				(pin passive line
					(at 0 -33.02 180)
					(length 3.81)
					(hide yes)
					(name "GND"
						(effects
							(font
								(size 1.27 1.27)
							)
						)
					)
					(number "A12"
						(effects
							(font
								(size 1.27 1.27)
							)
						)
					)
				)
				(pin passive line
					(at 0 -33.02 180)
					(length 3.81)
					(hide yes)
					(name "GND"
						(effects
							(font
								(size 1.27 1.27)
							)
						)
					)
					(number "B1"
						(effects
							(font
								(size 1.27 1.27)
							)
						)
					)
				)
				(pin passive line
					(at 0 -33.02 180)
					(length 3.81)
					(hide yes)
					(name "GND"
						(effects
							(font
								(size 1.27 1.27)
							)
						)
					)
					(number "B12"
						(effects
							(font
								(size 1.27 1.27)
							)
						)
					)
				)
				(pin passive line
					(at 0 -35.56 180)
					(length 3.81)
					(name "SH"
						(effects
							(font
								(size 1.27 1.27)
							)
						)
					)
					(number "SH"
						(effects
							(font
								(size 1.27 1.27)
							)
						)
					)
				)
			)
		)
	(symbol "antmicroWire2BoardConnectors:JST_SH_1x4_SM04B-SRSS-TB-LF-SN"
			(exclude_from_sim no)
			(in_bom yes)
			(on_board yes)
			(property "Reference" "J"
				(at 26.67 -2.54 0)
				(effects
					(font
						(size 1.27 1.27)
						(thickness 0.15)
					)
					(justify left bottom)
				)
			)
			(property "Value" "JST_SH_1x4_SM04B-SRSS-TB-LF-SN"
				(at 26.67 -7.62 0)
				(effects
					(font
						(size 1.27 1.27)
						(thickness 0.15)
					)
					(justify left bottom)
					(hide yes)
				)
			)
			(property "Footprint" "antmicro-footprints:Conn_JST_SH_1x4_SM04B-SRSS-TB-LF-SN"
				(at 26.67 -10.16 0)
				(effects
					(font
						(size 1.27 1.27)
						(thickness 0.15)
					)
					(justify left bottom)
					(hide yes)
				)
			)
			(property "Datasheet" "https://www.jst-mfg.com/product/pdf/eng/eSH.pdf"
				(at 26.67 -12.7 0)
				(effects
					(font
						(size 1.27 1.27)
						(thickness 0.15)
					)
					(justify left bottom)
					(hide yes)
				)
			)
			(property "Description" "Pin Header, Right Angle, Wire-to-Board, 1 mm, 1 Rows, 4 Contacts, Surface Mount Right Angle, SH"
				(at 26.67 -22.86 0)
				(effects
					(font
						(size 1.27 1.27)
					)
					(justify left bottom)
					(hide yes)
				)
			)
			(property "MPN" "SM04B-SRSS-TB(LF)(SN)"
				(at 26.67 -5.08 0)
				(effects
					(font
						(size 1.27 1.27)
						(thickness 0.15)
					)
					(justify left bottom)
				)
			)
			(property "Manufacturer" "JST Automotive Connectors"
				(at 26.67 -15.24 0)
				(effects
					(font
						(size 1.27 1.27)
						(thickness 0.15)
					)
					(justify left bottom)
					(hide yes)
				)
			)
			(property "Author" "Antmicro"
				(at 26.67 -17.78 0)
				(effects
					(font
						(size 1.27 1.27)
						(thickness 0.15)
					)
					(justify left bottom)
					(hide yes)
				)
			)
			(property "License" "Apache-2.0"
				(at 26.67 -20.32 0)
				(effects
					(font
						(size 1.27 1.27)
						(thickness 0.15)
					)
					(justify left bottom)
					(hide yes)
				)
			)
			(property "ki_keywords" "VERTICAL, SMT, WIRE-BOARD, CONNECTOR, MALE, HEADER"
				(at 0 0 0)
				(effects
					(font
						(size 1.27 1.27)
					)
					(hide yes)
				)
			)
			(symbol "JST_SH_1x4_SM04B-SRSS-TB-LF-SN_1_1"
				(rectangle
					(start 2.54 2.54)
					(end 5.08 -12.7)
					(stroke
						(width 0.254)
						(type default)
					)
					(fill
						(type background)
					)
				)
				(rectangle
					(start 2.54 0.127)
					(end 3.81 -0.127)
					(stroke
						(width 0.254)
						(type default)
					)
					(fill
						(type background)
					)
				)
				(rectangle
					(start 2.54 -2.413)
					(end 3.81 -2.667)
					(stroke
						(width 0.254)
						(type default)
					)
					(fill
						(type background)
					)
				)
				(rectangle
					(start 2.54 -4.953)
					(end 3.81 -5.207)
					(stroke
						(width 0.254)
						(type default)
					)
					(fill
						(type background)
					)
				)
				(rectangle
					(start 2.54 -7.493)
					(end 3.81 -7.747)
					(stroke
						(width 0.254)
						(type default)
					)
					(fill
						(type background)
					)
				)
				(rectangle
					(start 2.54 -10.033)
					(end 3.81 -10.287)
					(stroke
						(width 0.254)
						(type default)
					)
					(fill
						(type background)
					)
				)
				(pin passive line
					(at 0 0 0)
					(length 2.54)
					(name "~"
						(effects
							(font
								(size 1.27 1.27)
							)
						)
					)
					(number "1"
						(effects
							(font
								(size 1.27 1.27)
							)
						)
					)
				)
				(pin passive line
					(at 0 -2.54 0)
					(length 2.54)
					(name "~"
						(effects
							(font
								(size 1.27 1.27)
							)
						)
					)
					(number "2"
						(effects
							(font
								(size 1.27 1.27)
							)
						)
					)
				)
				(pin passive line
					(at 0 -5.08 0)
					(length 2.54)
					(name "~"
						(effects
							(font
								(size 1.27 1.27)
							)
						)
					)
					(number "3"
						(effects
							(font
								(size 1.27 1.27)
							)
						)
					)
				)
				(pin passive line
					(at 0 -7.62 0)
					(length 2.54)
					(name "~"
						(effects
							(font
								(size 1.27 1.27)
							)
						)
					)
					(number "4"
						(effects
							(font
								(size 1.27 1.27)
							)
						)
					)
				)
				(pin passive line
					(at 0 -10.16 0)
					(length 2.54)
					(name "~"
						(effects
							(font
								(size 1.27 1.27)
							)
						)
					)
					(number "MP"
						(effects
							(font
								(size 1.27 1.27)
							)
						)
					)
				)
			)
		)
	(symbol "antmicroWire2BoardConnectors:JST_SH_1x6_SM06B-SRSS-TB-LF-SN"
			(exclude_from_sim no)
			(in_bom yes)
			(on_board yes)
			(property "Reference" "J"
				(at 26.67 -2.54 0)
				(effects
					(font
						(size 1.27 1.27)
						(thickness 0.15)
					)
					(justify left bottom)
				)
			)
			(property "Value" "JST_SH_1x6_SM06B-SRSS-TB-LF-SN"
				(at 26.67 -7.62 0)
				(effects
					(font
						(size 1.27 1.27)
						(thickness 0.15)
					)
					(justify left bottom)
					(hide yes)
				)
			)
			(property "Footprint" "antmicro-footprints:Conn_JST_SH_1x6_SM06B-SRSS-TB-LF-SN"
				(at 26.67 -10.16 0)
				(effects
					(font
						(size 1.27 1.27)
						(thickness 0.15)
					)
					(justify left bottom)
					(hide yes)
				)
			)
			(property "Datasheet" "https://www.jst-mfg.com/product/pdf/eng/eSH.pdf"
				(at 26.67 -12.7 0)
				(effects
					(font
						(size 1.27 1.27)
						(thickness 0.15)
					)
					(justify left bottom)
					(hide yes)
				)
			)
			(property "Description" "Pin Header, Right Angle, Wire-to-Board, 1 mm, 1 Rows, 6 Contacts, Surface Mount Right Angle, SR"
				(at 26.67 -22.86 0)
				(effects
					(font
						(size 1.27 1.27)
					)
					(justify left bottom)
					(hide yes)
				)
			)
			(property "MPN" "SM06B-SRSS-TB(LF)(SN)"
				(at 26.67 -5.08 0)
				(effects
					(font
						(size 1.27 1.27)
						(thickness 0.15)
					)
					(justify left bottom)
				)
			)
			(property "Manufacturer" "JST Automotive Connectors"
				(at 26.67 -15.24 0)
				(effects
					(font
						(size 1.27 1.27)
						(thickness 0.15)
					)
					(justify left bottom)
					(hide yes)
				)
			)
			(property "Author" "Antmicro"
				(at 26.67 -17.78 0)
				(effects
					(font
						(size 1.27 1.27)
						(thickness 0.15)
					)
					(justify left bottom)
					(hide yes)
				)
			)
			(property "License" "Apache-2.0"
				(at 26.67 -20.32 0)
				(effects
					(font
						(size 1.27 1.27)
						(thickness 0.15)
					)
					(justify left bottom)
					(hide yes)
				)
			)
			(property "ki_keywords" "HORIZONTAL, SMT, WIRE-BOARD, CONNECTOR, MALE, HEADER"
				(at 0 0 0)
				(effects
					(font
						(size 1.27 1.27)
					)
					(hide yes)
				)
			)
			(symbol "JST_SH_1x6_SM06B-SRSS-TB-LF-SN_1_1"
				(rectangle
					(start 2.54 2.54)
					(end 5.08 -17.78)
					(stroke
						(width 0.254)
						(type default)
					)
					(fill
						(type background)
					)
				)
				(rectangle
					(start 2.54 0.127)
					(end 3.81 -0.127)
					(stroke
						(width 0.254)
						(type default)
					)
					(fill
						(type background)
					)
				)
				(rectangle
					(start 2.54 -2.413)
					(end 3.81 -2.667)
					(stroke
						(width 0.254)
						(type default)
					)
					(fill
						(type background)
					)
				)
				(rectangle
					(start 2.54 -4.953)
					(end 3.81 -5.207)
					(stroke
						(width 0.254)
						(type default)
					)
					(fill
						(type background)
					)
				)
				(rectangle
					(start 2.54 -7.493)
					(end 3.81 -7.747)
					(stroke
						(width 0.254)
						(type default)
					)
					(fill
						(type background)
					)
				)
				(rectangle
					(start 2.54 -10.033)
					(end 3.81 -10.287)
					(stroke
						(width 0.254)
						(type default)
					)
					(fill
						(type background)
					)
				)
				(rectangle
					(start 2.54 -12.573)
					(end 3.81 -12.827)
					(stroke
						(width 0.254)
						(type default)
					)
					(fill
						(type background)
					)
				)
				(rectangle
					(start 2.54 -15.113)
					(end 3.81 -15.367)
					(stroke
						(width 0.254)
						(type default)
					)
					(fill
						(type background)
					)
				)
				(pin passive line
					(at 0 0 0)
					(length 2.54)
					(name "~"
						(effects
							(font
								(size 1.27 1.27)
							)
						)
					)
					(number "1"
						(effects
							(font
								(size 1.27 1.27)
							)
						)
					)
				)
				(pin passive line
					(at 0 -2.54 0)
					(length 2.54)
					(name "~"
						(effects
							(font
								(size 1.27 1.27)
							)
						)
					)
					(number "2"
						(effects
							(font
								(size 1.27 1.27)
							)
						)
					)
				)
				(pin passive line
					(at 0 -5.08 0)
					(length 2.54)
					(name "~"
						(effects
							(font
								(size 1.27 1.27)
							)
						)
					)
					(number "3"
						(effects
							(font
								(size 1.27 1.27)
							)
						)
					)
				)
				(pin passive line
					(at 0 -7.62 0)
					(length 2.54)
					(name "~"
						(effects
							(font
								(size 1.27 1.27)
							)
						)
					)
					(number "4"
						(effects
							(font
								(size 1.27 1.27)
							)
						)
					)
				)
				(pin passive line
					(at 0 -10.16 0)
					(length 2.54)
					(name "~"
						(effects
							(font
								(size 1.27 1.27)
							)
						)
					)
					(number "5"
						(effects
							(font
								(size 1.27 1.27)
							)
						)
					)
				)
				(pin passive line
					(at 0 -12.7 0)
					(length 2.54)
					(name "~"
						(effects
							(font
								(size 1.27 1.27)
							)
						)
					)
					(number "6"
						(effects
							(font
								(size 1.27 1.27)
							)
						)
					)
				)
				(pin passive line
					(at 0 -15.24 0)
					(length 2.54)
					(name "~"
						(effects
							(font
								(size 1.27 1.27)
							)
						)
					)
					(number "MP"
						(effects
							(font
								(size 1.27 1.27)
							)
						)
					)
				)
			)
		)
	(symbol "antmicropower:+1V2"
			(power)
			(pin_names
				(offset 0)
			)
			(exclude_from_sim no)
			(in_bom yes)
			(on_board yes)
			(property "Reference" "#PWR"
				(at 0 -3.81 0)
				(effects
					(font
						(size 1.27 1.27)
					)
					(hide yes)
				)
			)
			(property "Value" "+1V2"
				(at 0 3.556 0)
				(effects
					(font
						(size 1.27 1.27)
					)
				)
			)
			(property "Footprint" ""
				(at 0 0 0)
				(effects
					(font
						(size 1.27 1.27)
					)
					(hide yes)
				)
			)
			(property "Datasheet" ""
				(at 0 0 0)
				(effects
					(font
						(size 1.27 1.27)
					)
					(hide yes)
				)
			)
			(property "Description" ""
				(at 0 -6.35 0)
				(effects
					(font
						(size 1.27 1.27)
					)
					(justify left bottom)
					(hide yes)
				)
			)
			(symbol "+1V2_0_1"
				(polyline
					(pts
						(xy -0.762 1.27) (xy 0 2.54)
					)
					(stroke
						(width 0)
						(type default)
					)
					(fill
						(type none)
					)
				)
				(polyline
					(pts
						(xy 0 2.54) (xy 0.762 1.27)
					)
					(stroke
						(width 0)
						(type default)
					)
					(fill
						(type none)
					)
				)
				(polyline
					(pts
						(xy 0 0) (xy 0 2.54)
					)
					(stroke
						(width 0)
						(type default)
					)
					(fill
						(type none)
					)
				)
			)
			(symbol "+1V2_1_1"
				(pin power_in line
					(at 0 0 90)
					(length 0)
					(hide yes)
					(name "+1V2"
						(effects
							(font
								(size 1.27 1.27)
							)
						)
					)
					(number "1"
						(effects
							(font
								(size 1.27 1.27)
							)
						)
					)
				)
			)
		)
	(symbol "antmicropower:+1V5"
			(power)
			(pin_names
				(offset 0)
			)
			(exclude_from_sim no)
			(in_bom yes)
			(on_board yes)
			(property "Reference" "#PWR"
				(at 0 -3.81 0)
				(effects
					(font
						(size 1.27 1.27)
					)
					(hide yes)
				)
			)
			(property "Value" "+1V5"
				(at 0 3.556 0)
				(effects
					(font
						(size 1.27 1.27)
					)
				)
			)
			(property "Footprint" ""
				(at 0 0 0)
				(effects
					(font
						(size 1.27 1.27)
					)
					(hide yes)
				)
			)
			(property "Datasheet" ""
				(at 0 0 0)
				(effects
					(font
						(size 1.27 1.27)
					)
					(hide yes)
				)
			)
			(property "Description" ""
				(at 0 -6.35 0)
				(effects
					(font
						(size 1.27 1.27)
					)
					(justify left bottom)
					(hide yes)
				)
			)
			(symbol "+1V5_0_1"
				(polyline
					(pts
						(xy -0.762 1.27) (xy 0 2.54)
					)
					(stroke
						(width 0)
						(type default)
					)
					(fill
						(type none)
					)
				)
				(polyline
					(pts
						(xy 0 2.54) (xy 0.762 1.27)
					)
					(stroke
						(width 0)
						(type default)
					)
					(fill
						(type none)
					)
				)
				(polyline
					(pts
						(xy 0 0) (xy 0 2.54)
					)
					(stroke
						(width 0)
						(type default)
					)
					(fill
						(type none)
					)
				)
			)
			(symbol "+1V5_1_1"
				(pin power_in line
					(at 0 0 90)
					(length 0)
					(hide yes)
					(name "+1V5"
						(effects
							(font
								(size 1.27 1.27)
							)
						)
					)
					(number "1"
						(effects
							(font
								(size 1.27 1.27)
							)
						)
					)
				)
			)
		)
	(symbol "antmicropower:+1V8"
			(power)
			(pin_numbers
				(hide yes)
			)
			(pin_names
				(hide yes)
			)
			(exclude_from_sim no)
			(in_bom yes)
			(on_board yes)
			(property "Reference" "#PWR"
				(at 15.24 -2.54 0)
				(effects
					(font
						(size 1.27 1.27)
						(thickness 0.15)
					)
					(justify left bottom)
					(hide yes)
				)
			)
			(property "Value" "+1V8"
				(at -3.175 2.54 0)
				(effects
					(font
						(size 1.27 1.27)
						(thickness 0.15)
					)
					(justify left bottom)
				)
			)
			(property "Footprint" ""
				(at 15.24 -7.62 0)
				(effects
					(font
						(size 1.27 1.27)
						(thickness 0.15)
					)
					(justify left bottom)
					(hide yes)
				)
			)
			(property "Datasheet" ""
				(at 15.24 -10.16 0)
				(effects
					(font
						(size 1.27 1.27)
						(thickness 0.15)
					)
					(justify left bottom)
					(hide yes)
				)
			)
			(property "Description" ""
				(at 15.24 -12.7 0)
				(effects
					(font
						(size 1.27 1.27)
					)
					(justify left bottom)
					(hide yes)
				)
			)
			(property "Author" "Antmicro"
				(at 15.24 -5.08 0)
				(effects
					(font
						(size 1.27 1.27)
						(thickness 0.15)
					)
					(justify left bottom)
					(hide yes)
				)
			)
			(property "License" "Apache-2.0"
				(at 15.24 -7.62 0)
				(effects
					(font
						(size 1.27 1.27)
						(thickness 0.15)
					)
					(justify left bottom)
					(hide yes)
				)
			)
			(symbol "+1V8_1_1"
				(polyline
					(pts
						(xy -0.762 1.27) (xy 0 2.54)
					)
					(stroke
						(width 0)
						(type default)
					)
					(fill
						(type background)
					)
				)
				(polyline
					(pts
						(xy 0 2.54) (xy 0.762 1.27)
					)
					(stroke
						(width 0)
						(type default)
					)
					(fill
						(type background)
					)
				)
				(polyline
					(pts
						(xy 0 0) (xy 0 2.54)
					)
					(stroke
						(width 0)
						(type default)
					)
					(fill
						(type background)
					)
				)
				(pin power_in line
					(at 0 0 90)
					(length 0)
					(hide yes)
					(name "+1V8"
						(effects
							(font
								(size 1.27 1.27)
							)
						)
					)
					(number "1"
						(effects
							(font
								(size 1.27 1.27)
							)
						)
					)
				)
			)
		)
	(symbol "antmicropower:+3.3V"
			(power)
			(pin_names
				(offset 0)
			)
			(exclude_from_sim no)
			(in_bom yes)
			(on_board yes)
			(property "Reference" "#PWR"
				(at 0 -3.81 0)
				(effects
					(font
						(size 1.27 1.27)
					)
					(hide yes)
				)
			)
			(property "Value" "+3.3V"
				(at 0 3.556 0)
				(effects
					(font
						(size 1.27 1.27)
					)
				)
			)
			(property "Footprint" ""
				(at 0 0 0)
				(effects
					(font
						(size 1.27 1.27)
					)
					(hide yes)
				)
			)
			(property "Datasheet" ""
				(at 0 0 0)
				(effects
					(font
						(size 1.27 1.27)
					)
					(hide yes)
				)
			)
			(property "Description" ""
				(at 0 -6.35 0)
				(effects
					(font
						(size 1.27 1.27)
					)
					(justify left bottom)
					(hide yes)
				)
			)
			(symbol "+3.3V_0_1"
				(polyline
					(pts
						(xy -0.762 1.27) (xy 0 2.54)
					)
					(stroke
						(width 0)
						(type default)
					)
					(fill
						(type none)
					)
				)
				(polyline
					(pts
						(xy 0 2.54) (xy 0.762 1.27)
					)
					(stroke
						(width 0)
						(type default)
					)
					(fill
						(type none)
					)
				)
				(polyline
					(pts
						(xy 0 0) (xy 0 2.54)
					)
					(stroke
						(width 0)
						(type default)
					)
					(fill
						(type none)
					)
				)
			)
			(symbol "+3.3V_1_1"
				(pin power_in line
					(at 0 0 90)
					(length 0)
					(hide yes)
					(name "+3V3"
						(effects
							(font
								(size 1.27 1.27)
							)
						)
					)
					(number "1"
						(effects
							(font
								(size 1.27 1.27)
							)
						)
					)
				)
			)
		)
	(symbol "antmicropower:+5V"
			(power)
			(pin_numbers
				(hide yes)
			)
			(pin_names
				(hide yes)
			)
			(exclude_from_sim no)
			(in_bom yes)
			(on_board yes)
			(property "Reference" "#PWR"
				(at 15.24 -2.54 0)
				(effects
					(font
						(size 1.27 1.27)
						(thickness 0.15)
					)
					(justify left bottom)
					(hide yes)
				)
			)
			(property "Value" "+5V"
				(at 15.24 -5.08 0)
				(effects
					(font
						(size 1.27 1.27)
						(thickness 0.15)
					)
					(justify left bottom)
				)
			)
			(property "Footprint" ""
				(at 15.24 -7.62 0)
				(effects
					(font
						(size 1.27 1.27)
						(thickness 0.15)
					)
					(justify left bottom)
					(hide yes)
				)
			)
			(property "Datasheet" ""
				(at 15.24 -10.16 0)
				(effects
					(font
						(size 1.27 1.27)
						(thickness 0.15)
					)
					(justify left bottom)
					(hide yes)
				)
			)
			(property "Description" ""
				(at 15.24 -12.7 0)
				(effects
					(font
						(size 1.27 1.27)
					)
					(justify left bottom)
					(hide yes)
				)
			)
			(property "Author" "Antmicro"
				(at 15.24 -7.62 0)
				(effects
					(font
						(size 1.27 1.27)
						(thickness 0.15)
					)
					(justify left bottom)
					(hide yes)
				)
			)
			(property "License" "Apache-2.0"
				(at 15.24 -10.16 0)
				(effects
					(font
						(size 1.27 1.27)
						(thickness 0.15)
					)
					(justify left bottom)
					(hide yes)
				)
			)
			(symbol "+5V_1_1"
				(polyline
					(pts
						(xy -0.762 1.27) (xy 0 2.54)
					)
					(stroke
						(width 0)
						(type default)
					)
					(fill
						(type background)
					)
				)
				(polyline
					(pts
						(xy 0 2.54) (xy 0.762 1.27)
					)
					(stroke
						(width 0)
						(type default)
					)
					(fill
						(type background)
					)
				)
				(polyline
					(pts
						(xy 0 0) (xy 0 2.54)
					)
					(stroke
						(width 0)
						(type default)
					)
					(fill
						(type background)
					)
				)
				(pin power_in line
					(at 0 0 90)
					(length 0)
					(name "+5V"
						(effects
							(font
								(size 1.27 1.27)
							)
						)
					)
					(number "1"
						(effects
							(font
								(size 1.27 1.27)
							)
						)
					)
				)
			)
		)
	(symbol "antmicropower:GND"
			(power)
			(pin_numbers
				(hide yes)
			)
			(pin_names
				(hide yes)
			)
			(exclude_from_sim no)
			(in_bom yes)
			(on_board yes)
			(property "Reference" "#PWR"
				(at 8.89 -2.54 0)
				(effects
					(font
						(size 1.27 1.27)
						(thickness 0.15)
					)
					(justify left bottom)
					(hide yes)
				)
			)
			(property "Value" "GND"
				(at 8.89 -5.08 0)
				(effects
					(font
						(size 1.27 1.27)
						(thickness 0.15)
					)
					(justify left bottom)
				)
			)
			(property "Footprint" ""
				(at 8.89 -7.62 0)
				(effects
					(font
						(size 1.27 1.27)
						(thickness 0.15)
					)
					(justify left bottom)
					(hide yes)
				)
			)
			(property "Datasheet" ""
				(at 8.89 -12.7 0)
				(effects
					(font
						(size 1.27 1.27)
						(thickness 0.15)
					)
					(justify left bottom)
					(hide yes)
				)
			)
			(property "Description" ""
				(at 8.89 -15.24 0)
				(effects
					(font
						(size 1.27 1.27)
					)
					(justify left bottom)
					(hide yes)
				)
			)
			(property "Author" "Antmicro"
				(at 8.89 -7.62 0)
				(effects
					(font
						(size 1.27 1.27)
						(thickness 0.15)
					)
					(justify left bottom)
					(hide yes)
				)
			)
			(property "License" "Apache-2.0"
				(at 8.89 -10.16 0)
				(effects
					(font
						(size 1.27 1.27)
						(thickness 0.15)
					)
					(justify left bottom)
					(hide yes)
				)
			)
			(symbol "GND_1_1"
				(polyline
					(pts
						(xy 0 0) (xy 0 -1.27) (xy 1.27 -1.27) (xy 0 -2.54) (xy -1.27 -1.27) (xy 0 -1.27)
					)
					(stroke
						(width 0)
						(type default)
					)
					(fill
						(type none)
					)
				)
				(pin power_in line
					(at 0 0 270)
					(length 0)
					(name "GND"
						(effects
							(font
								(size 1.27 1.27)
							)
						)
					)
					(number "1"
						(effects
							(font
								(size 1.27 1.27)
							)
						)
					)
				)
			)
		)
	(symbol "sdi-mipi-video-converter:WE_68715014522_ONE-SIDE_1"
			(pin_names
				(offset 1.016)
				(hide yes)
			)
			(exclude_from_sim no)
			(in_bom yes)
			(on_board yes)
			(property "Reference" "J"
				(at 0 43.18 0)
				(effects
					(font
						(size 1.27 1.27)
					)
				)
			)
			(property "Value" "WE_68715014522_ONE-SIDE_1"
				(at -2.54 -96.52 0)
				(effects
					(font
						(size 1.27 1.27)
					)
				)
			)
			(property "Footprint" "sdi-mipi-video-converter-footprints:WE_68715014522_ONE-SIDE"
				(at -5.08 -99.06 0)
				(effects
					(font
						(size 1.27 1.27)
					)
					(hide yes)
				)
			)
			(property "Datasheet" ""
				(at 0 -101.6 0)
				(effects
					(font
						(size 1.27 1.27)
					)
					(hide yes)
				)
			)
			(property "Description" ""
				(at 0 0 0)
				(effects
					(font
						(size 1.27 1.27)
					)
					(hide yes)
				)
			)
			(property "MPN" "68715014522 "
				(at 10.16 -15.24 0)
				(effects
					(font
						(size 1.524 1.524)
					)
					(justify left)
					(hide yes)
				)
			)
			(property "Manufacturer" "Wurth Elektronik "
				(at 16.51 -45.72 0)
				(effects
					(font
						(size 1.524 1.524)
					)
					(justify left)
					(hide yes)
				)
			)
			(symbol "WE_68715014522_ONE-SIDE_1_1_1"
				(rectangle
					(start -1.27 41.91)
					(end 1.27 -87.63)
					(stroke
						(width 0.254)
						(type default)
					)
					(fill
						(type background)
					)
				)
				(rectangle
					(start -1.27 40.767)
					(end 0 40.513)
					(stroke
						(width 0.1524)
						(type default)
					)
					(fill
						(type none)
					)
				)
				(rectangle
					(start -1.27 38.227)
					(end 0 37.973)
					(stroke
						(width 0.1524)
						(type default)
					)
					(fill
						(type none)
					)
				)
				(rectangle
					(start -1.27 35.687)
					(end 0 35.433)
					(stroke
						(width 0.1524)
						(type default)
					)
					(fill
						(type none)
					)
				)
				(rectangle
					(start -1.27 33.147)
					(end 0 32.893)
					(stroke
						(width 0.1524)
						(type default)
					)
					(fill
						(type none)
					)
				)
				(rectangle
					(start -1.27 30.607)
					(end 0 30.353)
					(stroke
						(width 0.1524)
						(type default)
					)
					(fill
						(type none)
					)
				)
				(rectangle
					(start -1.27 28.067)
					(end 0 27.813)
					(stroke
						(width 0.1524)
						(type default)
					)
					(fill
						(type none)
					)
				)
				(rectangle
					(start -1.27 25.527)
					(end 0 25.273)
					(stroke
						(width 0.1524)
						(type default)
					)
					(fill
						(type none)
					)
				)
				(rectangle
					(start -1.27 22.987)
					(end 0 22.733)
					(stroke
						(width 0.1524)
						(type default)
					)
					(fill
						(type none)
					)
				)
				(rectangle
					(start -1.27 20.447)
					(end 0 20.193)
					(stroke
						(width 0.1524)
						(type default)
					)
					(fill
						(type none)
					)
				)
				(rectangle
					(start -1.27 17.907)
					(end 0 17.653)
					(stroke
						(width 0.1524)
						(type default)
					)
					(fill
						(type none)
					)
				)
				(rectangle
					(start -1.27 15.367)
					(end 0 15.113)
					(stroke
						(width 0.1524)
						(type default)
					)
					(fill
						(type none)
					)
				)
				(rectangle
					(start -1.27 12.827)
					(end 0 12.573)
					(stroke
						(width 0.1524)
						(type default)
					)
					(fill
						(type none)
					)
				)
				(rectangle
					(start -1.27 10.287)
					(end 0 10.033)
					(stroke
						(width 0.1524)
						(type default)
					)
					(fill
						(type none)
					)
				)
				(rectangle
					(start -1.27 7.747)
					(end 0 7.493)
					(stroke
						(width 0.1524)
						(type default)
					)
					(fill
						(type none)
					)
				)
				(rectangle
					(start -1.27 5.207)
					(end 0 4.953)
					(stroke
						(width 0.1524)
						(type default)
					)
					(fill
						(type none)
					)
				)
				(rectangle
					(start -1.27 2.667)
					(end 0 2.413)
					(stroke
						(width 0.1524)
						(type default)
					)
					(fill
						(type none)
					)
				)
				(rectangle
					(start -1.27 0.127)
					(end 0 -0.127)
					(stroke
						(width 0.1524)
						(type default)
					)
					(fill
						(type none)
					)
				)
				(rectangle
					(start -1.27 -2.413)
					(end 0 -2.667)
					(stroke
						(width 0.1524)
						(type default)
					)
					(fill
						(type none)
					)
				)
				(rectangle
					(start -1.27 -4.953)
					(end 0 -5.207)
					(stroke
						(width 0.1524)
						(type default)
					)
					(fill
						(type none)
					)
				)
				(rectangle
					(start -1.27 -7.493)
					(end 0 -7.747)
					(stroke
						(width 0.1524)
						(type default)
					)
					(fill
						(type none)
					)
				)
				(rectangle
					(start -1.27 -10.033)
					(end 0 -10.287)
					(stroke
						(width 0.1524)
						(type default)
					)
					(fill
						(type none)
					)
				)
				(rectangle
					(start -1.27 -12.573)
					(end 0 -12.827)
					(stroke
						(width 0.1524)
						(type default)
					)
					(fill
						(type none)
					)
				)
				(rectangle
					(start -1.27 -15.113)
					(end 0 -15.367)
					(stroke
						(width 0.1524)
						(type default)
					)
					(fill
						(type none)
					)
				)
				(rectangle
					(start -1.27 -17.653)
					(end 0 -17.907)
					(stroke
						(width 0.1524)
						(type default)
					)
					(fill
						(type none)
					)
				)
				(rectangle
					(start -1.27 -20.193)
					(end 0 -20.447)
					(stroke
						(width 0.1524)
						(type default)
					)
					(fill
						(type none)
					)
				)
				(rectangle
					(start -1.27 -22.733)
					(end 0 -22.987)
					(stroke
						(width 0.1524)
						(type default)
					)
					(fill
						(type none)
					)
				)
				(rectangle
					(start -1.27 -25.273)
					(end 0 -25.527)
					(stroke
						(width 0.1524)
						(type default)
					)
					(fill
						(type none)
					)
				)
				(rectangle
					(start -1.27 -27.813)
					(end 0 -28.067)
					(stroke
						(width 0.1524)
						(type default)
					)
					(fill
						(type none)
					)
				)
				(rectangle
					(start -1.27 -30.353)
					(end 0 -30.607)
					(stroke
						(width 0.1524)
						(type default)
					)
					(fill
						(type none)
					)
				)
				(rectangle
					(start -1.27 -32.893)
					(end 0 -33.147)
					(stroke
						(width 0.1524)
						(type default)
					)
					(fill
						(type none)
					)
				)
				(rectangle
					(start -1.27 -35.433)
					(end 0 -35.687)
					(stroke
						(width 0.1524)
						(type default)
					)
					(fill
						(type none)
					)
				)
				(rectangle
					(start -1.27 -37.973)
					(end 0 -38.227)
					(stroke
						(width 0.1524)
						(type default)
					)
					(fill
						(type none)
					)
				)
				(rectangle
					(start -1.27 -40.513)
					(end 0 -40.767)
					(stroke
						(width 0.1524)
						(type default)
					)
					(fill
						(type none)
					)
				)
				(rectangle
					(start -1.27 -43.053)
					(end 0 -43.307)
					(stroke
						(width 0.1524)
						(type default)
					)
					(fill
						(type none)
					)
				)
				(rectangle
					(start -1.27 -45.593)
					(end 0 -45.847)
					(stroke
						(width 0.1524)
						(type default)
					)
					(fill
						(type none)
					)
				)
				(rectangle
					(start -1.27 -48.133)
					(end 0 -48.387)
					(stroke
						(width 0.1524)
						(type default)
					)
					(fill
						(type none)
					)
				)
				(rectangle
					(start -1.27 -50.673)
					(end 0 -50.927)
					(stroke
						(width 0.1524)
						(type default)
					)
					(fill
						(type none)
					)
				)
				(rectangle
					(start -1.27 -53.213)
					(end 0 -53.467)
					(stroke
						(width 0.1524)
						(type default)
					)
					(fill
						(type none)
					)
				)
				(rectangle
					(start -1.27 -55.753)
					(end 0 -56.007)
					(stroke
						(width 0.1524)
						(type default)
					)
					(fill
						(type none)
					)
				)
				(rectangle
					(start -1.27 -58.293)
					(end 0 -58.547)
					(stroke
						(width 0.1524)
						(type default)
					)
					(fill
						(type none)
					)
				)
				(rectangle
					(start -1.27 -60.833)
					(end 0 -61.087)
					(stroke
						(width 0.1524)
						(type default)
					)
					(fill
						(type none)
					)
				)
				(rectangle
					(start -1.27 -63.373)
					(end 0 -63.627)
					(stroke
						(width 0.1524)
						(type default)
					)
					(fill
						(type none)
					)
				)
				(rectangle
					(start -1.27 -65.913)
					(end 0 -66.167)
					(stroke
						(width 0.1524)
						(type default)
					)
					(fill
						(type none)
					)
				)
				(rectangle
					(start -1.27 -68.453)
					(end 0 -68.707)
					(stroke
						(width 0.1524)
						(type default)
					)
					(fill
						(type none)
					)
				)
				(rectangle
					(start -1.27 -70.993)
					(end 0 -71.247)
					(stroke
						(width 0.1524)
						(type default)
					)
					(fill
						(type none)
					)
				)
				(rectangle
					(start -1.27 -73.533)
					(end 0 -73.787)
					(stroke
						(width 0.1524)
						(type default)
					)
					(fill
						(type none)
					)
				)
				(rectangle
					(start -1.27 -76.073)
					(end 0 -76.327)
					(stroke
						(width 0.1524)
						(type default)
					)
					(fill
						(type none)
					)
				)
				(rectangle
					(start -1.27 -78.613)
					(end 0 -78.867)
					(stroke
						(width 0.1524)
						(type default)
					)
					(fill
						(type none)
					)
				)
				(rectangle
					(start -1.27 -81.153)
					(end 0 -81.407)
					(stroke
						(width 0.1524)
						(type default)
					)
					(fill
						(type none)
					)
				)
				(rectangle
					(start -1.27 -83.693)
					(end 0 -83.947)
					(stroke
						(width 0.1524)
						(type default)
					)
					(fill
						(type none)
					)
				)
				(pin passive line
					(at -5.08 40.64 0)
					(length 3.81)
					(name "Pin_1"
						(effects
							(font
								(size 1.27 1.27)
							)
						)
					)
					(number "1"
						(effects
							(font
								(size 1.27 1.27)
							)
						)
					)
				)
				(pin passive line
					(at -5.08 38.1 0)
					(length 3.81)
					(name "Pin_2"
						(effects
							(font
								(size 1.27 1.27)
							)
						)
					)
					(number "2"
						(effects
							(font
								(size 1.27 1.27)
							)
						)
					)
				)
				(pin passive line
					(at -5.08 35.56 0)
					(length 3.81)
					(name "Pin_3"
						(effects
							(font
								(size 1.27 1.27)
							)
						)
					)
					(number "3"
						(effects
							(font
								(size 1.27 1.27)
							)
						)
					)
				)
				(pin passive line
					(at -5.08 33.02 0)
					(length 3.81)
					(name "Pin_4"
						(effects
							(font
								(size 1.27 1.27)
							)
						)
					)
					(number "4"
						(effects
							(font
								(size 1.27 1.27)
							)
						)
					)
				)
				(pin passive line
					(at -5.08 30.48 0)
					(length 3.81)
					(name "Pin_5"
						(effects
							(font
								(size 1.27 1.27)
							)
						)
					)
					(number "5"
						(effects
							(font
								(size 1.27 1.27)
							)
						)
					)
				)
				(pin passive line
					(at -5.08 27.94 0)
					(length 3.81)
					(name "Pin_6"
						(effects
							(font
								(size 1.27 1.27)
							)
						)
					)
					(number "6"
						(effects
							(font
								(size 1.27 1.27)
							)
						)
					)
				)
				(pin passive line
					(at -5.08 25.4 0)
					(length 3.81)
					(name "Pin_7"
						(effects
							(font
								(size 1.27 1.27)
							)
						)
					)
					(number "7"
						(effects
							(font
								(size 1.27 1.27)
							)
						)
					)
				)
				(pin passive line
					(at -5.08 22.86 0)
					(length 3.81)
					(name "Pin_8"
						(effects
							(font
								(size 1.27 1.27)
							)
						)
					)
					(number "8"
						(effects
							(font
								(size 1.27 1.27)
							)
						)
					)
				)
				(pin passive line
					(at -5.08 20.32 0)
					(length 3.81)
					(name "Pin_9"
						(effects
							(font
								(size 1.27 1.27)
							)
						)
					)
					(number "9"
						(effects
							(font
								(size 1.27 1.27)
							)
						)
					)
				)
				(pin passive line
					(at -5.08 17.78 0)
					(length 3.81)
					(name "Pin_10"
						(effects
							(font
								(size 1.27 1.27)
							)
						)
					)
					(number "10"
						(effects
							(font
								(size 1.27 1.27)
							)
						)
					)
				)
				(pin passive line
					(at -5.08 15.24 0)
					(length 3.81)
					(name "Pin_11"
						(effects
							(font
								(size 1.27 1.27)
							)
						)
					)
					(number "11"
						(effects
							(font
								(size 1.27 1.27)
							)
						)
					)
				)
				(pin passive line
					(at -5.08 12.7 0)
					(length 3.81)
					(name "Pin_12"
						(effects
							(font
								(size 1.27 1.27)
							)
						)
					)
					(number "12"
						(effects
							(font
								(size 1.27 1.27)
							)
						)
					)
				)
				(pin passive line
					(at -5.08 10.16 0)
					(length 3.81)
					(name "Pin_13"
						(effects
							(font
								(size 1.27 1.27)
							)
						)
					)
					(number "13"
						(effects
							(font
								(size 1.27 1.27)
							)
						)
					)
				)
				(pin passive line
					(at -5.08 7.62 0)
					(length 3.81)
					(name "Pin_14"
						(effects
							(font
								(size 1.27 1.27)
							)
						)
					)
					(number "14"
						(effects
							(font
								(size 1.27 1.27)
							)
						)
					)
				)
				(pin passive line
					(at -5.08 5.08 0)
					(length 3.81)
					(name "Pin_15"
						(effects
							(font
								(size 1.27 1.27)
							)
						)
					)
					(number "15"
						(effects
							(font
								(size 1.27 1.27)
							)
						)
					)
				)
				(pin passive line
					(at -5.08 2.54 0)
					(length 3.81)
					(name "Pin_16"
						(effects
							(font
								(size 1.27 1.27)
							)
						)
					)
					(number "16"
						(effects
							(font
								(size 1.27 1.27)
							)
						)
					)
				)
				(pin passive line
					(at -5.08 0 0)
					(length 3.81)
					(name "Pin_17"
						(effects
							(font
								(size 1.27 1.27)
							)
						)
					)
					(number "17"
						(effects
							(font
								(size 1.27 1.27)
							)
						)
					)
				)
				(pin passive line
					(at -5.08 -2.54 0)
					(length 3.81)
					(name "Pin_18"
						(effects
							(font
								(size 1.27 1.27)
							)
						)
					)
					(number "18"
						(effects
							(font
								(size 1.27 1.27)
							)
						)
					)
				)
				(pin passive line
					(at -5.08 -5.08 0)
					(length 3.81)
					(name "Pin_19"
						(effects
							(font
								(size 1.27 1.27)
							)
						)
					)
					(number "19"
						(effects
							(font
								(size 1.27 1.27)
							)
						)
					)
				)
				(pin passive line
					(at -5.08 -7.62 0)
					(length 3.81)
					(name "Pin_20"
						(effects
							(font
								(size 1.27 1.27)
							)
						)
					)
					(number "20"
						(effects
							(font
								(size 1.27 1.27)
							)
						)
					)
				)
				(pin passive line
					(at -5.08 -10.16 0)
					(length 3.81)
					(name "Pin_21"
						(effects
							(font
								(size 1.27 1.27)
							)
						)
					)
					(number "21"
						(effects
							(font
								(size 1.27 1.27)
							)
						)
					)
				)
				(pin passive line
					(at -5.08 -12.7 0)
					(length 3.81)
					(name "Pin_22"
						(effects
							(font
								(size 1.27 1.27)
							)
						)
					)
					(number "22"
						(effects
							(font
								(size 1.27 1.27)
							)
						)
					)
				)
				(pin passive line
					(at -5.08 -15.24 0)
					(length 3.81)
					(name "Pin_23"
						(effects
							(font
								(size 1.27 1.27)
							)
						)
					)
					(number "23"
						(effects
							(font
								(size 1.27 1.27)
							)
						)
					)
				)
				(pin passive line
					(at -5.08 -17.78 0)
					(length 3.81)
					(name "Pin_24"
						(effects
							(font
								(size 1.27 1.27)
							)
						)
					)
					(number "24"
						(effects
							(font
								(size 1.27 1.27)
							)
						)
					)
				)
				(pin passive line
					(at -5.08 -20.32 0)
					(length 3.81)
					(name "Pin_25"
						(effects
							(font
								(size 1.27 1.27)
							)
						)
					)
					(number "25"
						(effects
							(font
								(size 1.27 1.27)
							)
						)
					)
				)
				(pin passive line
					(at -5.08 -22.86 0)
					(length 3.81)
					(name "Pin_26"
						(effects
							(font
								(size 1.27 1.27)
							)
						)
					)
					(number "26"
						(effects
							(font
								(size 1.27 1.27)
							)
						)
					)
				)
				(pin passive line
					(at -5.08 -25.4 0)
					(length 3.81)
					(name "Pin_27"
						(effects
							(font
								(size 1.27 1.27)
							)
						)
					)
					(number "27"
						(effects
							(font
								(size 1.27 1.27)
							)
						)
					)
				)
				(pin passive line
					(at -5.08 -27.94 0)
					(length 3.81)
					(name "Pin_28"
						(effects
							(font
								(size 1.27 1.27)
							)
						)
					)
					(number "28"
						(effects
							(font
								(size 1.27 1.27)
							)
						)
					)
				)
				(pin passive line
					(at -5.08 -30.48 0)
					(length 3.81)
					(name "Pin_29"
						(effects
							(font
								(size 1.27 1.27)
							)
						)
					)
					(number "29"
						(effects
							(font
								(size 1.27 1.27)
							)
						)
					)
				)
				(pin passive line
					(at -5.08 -33.02 0)
					(length 3.81)
					(name "Pin_30"
						(effects
							(font
								(size 1.27 1.27)
							)
						)
					)
					(number "30"
						(effects
							(font
								(size 1.27 1.27)
							)
						)
					)
				)
				(pin passive line
					(at -5.08 -35.56 0)
					(length 3.81)
					(name "Pin_31"
						(effects
							(font
								(size 1.27 1.27)
							)
						)
					)
					(number "31"
						(effects
							(font
								(size 1.27 1.27)
							)
						)
					)
				)
				(pin passive line
					(at -5.08 -38.1 0)
					(length 3.81)
					(name "Pin_32"
						(effects
							(font
								(size 1.27 1.27)
							)
						)
					)
					(number "32"
						(effects
							(font
								(size 1.27 1.27)
							)
						)
					)
				)
				(pin passive line
					(at -5.08 -40.64 0)
					(length 3.81)
					(name "Pin_33"
						(effects
							(font
								(size 1.27 1.27)
							)
						)
					)
					(number "33"
						(effects
							(font
								(size 1.27 1.27)
							)
						)
					)
				)
				(pin passive line
					(at -5.08 -43.18 0)
					(length 3.81)
					(name "Pin_34"
						(effects
							(font
								(size 1.27 1.27)
							)
						)
					)
					(number "34"
						(effects
							(font
								(size 1.27 1.27)
							)
						)
					)
				)
				(pin passive line
					(at -5.08 -45.72 0)
					(length 3.81)
					(name "Pin_35"
						(effects
							(font
								(size 1.27 1.27)
							)
						)
					)
					(number "35"
						(effects
							(font
								(size 1.27 1.27)
							)
						)
					)
				)
				(pin passive line
					(at -5.08 -48.26 0)
					(length 3.81)
					(name "Pin_36"
						(effects
							(font
								(size 1.27 1.27)
							)
						)
					)
					(number "36"
						(effects
							(font
								(size 1.27 1.27)
							)
						)
					)
				)
				(pin passive line
					(at -5.08 -50.8 0)
					(length 3.81)
					(name "Pin_37"
						(effects
							(font
								(size 1.27 1.27)
							)
						)
					)
					(number "37"
						(effects
							(font
								(size 1.27 1.27)
							)
						)
					)
				)
				(pin passive line
					(at -5.08 -53.34 0)
					(length 3.81)
					(name "Pin_38"
						(effects
							(font
								(size 1.27 1.27)
							)
						)
					)
					(number "38"
						(effects
							(font
								(size 1.27 1.27)
							)
						)
					)
				)
				(pin passive line
					(at -5.08 -55.88 0)
					(length 3.81)
					(name "Pin_39"
						(effects
							(font
								(size 1.27 1.27)
							)
						)
					)
					(number "39"
						(effects
							(font
								(size 1.27 1.27)
							)
						)
					)
				)
				(pin passive line
					(at -5.08 -58.42 0)
					(length 3.81)
					(name "Pin_40"
						(effects
							(font
								(size 1.27 1.27)
							)
						)
					)
					(number "40"
						(effects
							(font
								(size 1.27 1.27)
							)
						)
					)
				)
				(pin passive line
					(at -5.08 -60.96 0)
					(length 3.81)
					(name "Pin_41"
						(effects
							(font
								(size 1.27 1.27)
							)
						)
					)
					(number "41"
						(effects
							(font
								(size 1.27 1.27)
							)
						)
					)
				)
				(pin passive line
					(at -5.08 -63.5 0)
					(length 3.81)
					(name "Pin_42"
						(effects
							(font
								(size 1.27 1.27)
							)
						)
					)
					(number "42"
						(effects
							(font
								(size 1.27 1.27)
							)
						)
					)
				)
				(pin passive line
					(at -5.08 -66.04 0)
					(length 3.81)
					(name "Pin_43"
						(effects
							(font
								(size 1.27 1.27)
							)
						)
					)
					(number "43"
						(effects
							(font
								(size 1.27 1.27)
							)
						)
					)
				)
				(pin passive line
					(at -5.08 -68.58 0)
					(length 3.81)
					(name "Pin_44"
						(effects
							(font
								(size 1.27 1.27)
							)
						)
					)
					(number "44"
						(effects
							(font
								(size 1.27 1.27)
							)
						)
					)
				)
				(pin passive line
					(at -5.08 -71.12 0)
					(length 3.81)
					(name "Pin_45"
						(effects
							(font
								(size 1.27 1.27)
							)
						)
					)
					(number "45"
						(effects
							(font
								(size 1.27 1.27)
							)
						)
					)
				)
				(pin passive line
					(at -5.08 -73.66 0)
					(length 3.81)
					(name "Pin_46"
						(effects
							(font
								(size 1.27 1.27)
							)
						)
					)
					(number "46"
						(effects
							(font
								(size 1.27 1.27)
							)
						)
					)
				)
				(pin passive line
					(at -5.08 -76.2 0)
					(length 3.81)
					(name "Pin_47"
						(effects
							(font
								(size 1.27 1.27)
							)
						)
					)
					(number "47"
						(effects
							(font
								(size 1.27 1.27)
							)
						)
					)
				)
				(pin passive line
					(at -5.08 -78.74 0)
					(length 3.81)
					(name "Pin_48"
						(effects
							(font
								(size 1.27 1.27)
							)
						)
					)
					(number "48"
						(effects
							(font
								(size 1.27 1.27)
							)
						)
					)
				)
				(pin passive line
					(at -5.08 -81.28 0)
					(length 3.81)
					(name "Pin_49"
						(effects
							(font
								(size 1.27 1.27)
							)
						)
					)
					(number "49"
						(effects
							(font
								(size 1.27 1.27)
							)
						)
					)
				)
				(pin passive line
					(at -5.08 -83.82 0)
					(length 3.81)
					(name "Pin_50"
						(effects
							(font
								(size 1.27 1.27)
							)
						)
					)
					(number "50"
						(effects
							(font
								(size 1.27 1.27)
							)
						)
					)
				)
				(pin passive line
					(at -5.08 -86.36 0)
					(length 3.81)
					(name "SHLD"
						(effects
							(font
								(size 1.27 1.27)
							)
						)
					)
					(number "SH"
						(effects
							(font
								(size 1.27 1.27)
							)
						)
					)
				)
			)
		)
)
